G04 ================== begin FILE IDENTIFICATION RECORD ==================*
G04 Layout Name:  D:/<user>/Wistron_project/16317-1/gbr/16317-1.brd*
G04 Film Name:    BSILK*
G04 File Format:  Gerber RS274X*
G04 File Origin:  Cadence Allegro 16.5-S056*
G04 Origin Date:  Fri Jun 09 15:52:38 2017*
G04 *
G04 Layer:  VIA CLASS/FILMMASKBOTTOM*
G04 Layer:  REF DES/ASSEMBLY_BOTTOM*
G04 Layer:  PACKAGE GEOMETRY/SILKSCREEN_BOTTOM*
G04 Layer:  DRAWING FORMAT/LAYER_PCB_STORY*
G04 Layer:  DRAWING FORMAT/LAYER_SILK_B*
G04 Layer:  BOARD GEOMETRY/SILKSCREEN_BOTTOM*
G04 *
G04 Offset:    (0.00 0.00)*
G04 Mirror:    No*
G04 Mode:      Positive*
G04 Rotation:  0*
G04 FullContactRelief:  No*
G04 UndefLineWidth:     6.00*
G04 ================== end FILE IDENTIFICATION RECORD ====================*
%FSLAX35Y35*MOIN*%
%IR0*IPPOS*OFA0.00000B0.00000*MIA0B0*SFA1.00000B1.00000*%
%ADD10C,.026*%
%ADD11C,.02*%
%ADD12C,.013*%
%ADD13C,.015*%
%ADD14C,.006*%
%ADD15C,.008*%
G75*
%LPD*%
G75*
G36*
G01X98850Y899500D02*
Y895450D01*
X94800Y899500D01*
X98850D01*
G37*
G36*
G01X196677Y461764D02*
Y457714D01*
X192627Y461764D01*
X196677D01*
G37*
G36*
G01X815631Y1321885D02*
Y1318485D01*
X813931Y1320185D01*
X815631Y1321885D01*
G37*
G36*
G01X816101Y1364391D02*
Y1360991D01*
X814401Y1362691D01*
X816101Y1364391D01*
G37*
G36*
G01X815880Y1402059D02*
Y1398659D01*
X814180Y1400359D01*
X815880Y1402059D01*
G37*
G36*
G01X1011587Y1121399D02*
Y1116399D01*
X1006587Y1121399D01*
X1011587D01*
G37*
G36*
G01X1739446Y465182D02*
Y461132D01*
X1735396Y465182D01*
X1739446D01*
G37*
G36*
G01X1813850Y899500D02*
Y895450D01*
X1809800Y899500D01*
X1813850D01*
G37*
G54D10*
X685000Y1453500D03*
X690000Y1448500D03*
X695000Y1453500D03*
X690000Y1458500D03*
Y1453500D03*
X957000Y1207500D03*
X953100Y1211400D03*
X953000Y1203600D03*
X960900Y1211400D03*
Y1203600D03*
X992443Y1441399D03*
X1002443D03*
X997443Y1436399D03*
Y1446399D03*
Y1441399D03*
X1124612Y1388773D03*
G54D11*
G01X59263Y878025D02*
X54263D01*
G01X51263D02*
X46263D01*
G01X43263D02*
X38263D01*
G01X60763Y896525D02*
Y891525D01*
G01X157090Y440289D02*
X152090D01*
G01X149090D02*
X144090D01*
G01X141090D02*
X136090D01*
G01X158590Y458789D02*
Y453789D01*
G01X178263Y899025D02*
X173263D01*
G01X194263D02*
X189263D01*
G01X186263D02*
X181263D01*
G01X153500Y884485D02*
X170100D01*
G01Y886785D02*
X153500D01*
G01X276090Y461289D02*
X271090D01*
G01X292090D02*
X287090D01*
G01X284090D02*
X279090D01*
G01X251327Y447149D02*
X267927D01*
G01Y449449D02*
X251327D01*
G01X466941Y-145664D02*
Y-225664D01*
G01D02*
X1593241D01*
G01X462941Y-129664D02*
G02I-12000J0D01*
G01X457791D02*
G02I-6850J0D01*
G01X450941Y-145664D02*
Y-113664D01*
G01X466941Y-129664D02*
X434941D01*
G01X466941Y-145664D02*
X1593241D01*
G01X466941Y-181164D02*
X1593241D01*
G01X504699Y1441655D02*
X498699D01*
G01X715300Y1461100D02*
Y1466100D01*
G01X805741Y-145664D02*
Y-225664D01*
G01X943241Y-145664D02*
Y-225664D01*
G01X947661Y1096299D02*
Y1091299D01*
G01X947500Y1104200D02*
Y1099200D01*
G01X947600Y1112100D02*
Y1107100D01*
G01X947000Y1126000D02*
X942000D01*
G01X955000D02*
X950000D01*
G01X963000D02*
X958000D01*
G01X991000Y1139000D02*
Y1134000D01*
G01Y1147000D02*
Y1142000D01*
G01X1058241Y-145664D02*
Y-225664D01*
G01X1225741Y-145664D02*
Y-225664D01*
G01X1395741Y-145664D02*
Y-225664D01*
G01X1593241Y-145664D02*
Y-225664D01*
G01X1621241Y-129664D02*
G02I-12000J0D01*
G01X1616091D02*
G02I-6850J0D01*
G01X1609241Y-145664D02*
Y-113664D01*
G01X1625241Y-129664D02*
X1593241D01*
G01X1699859Y443707D02*
X1694859D01*
G01X1691859D02*
X1686859D01*
G01X1683859D02*
X1678859D01*
G01X1701359Y462207D02*
Y457207D01*
G01X1818838Y464623D02*
X1813838D01*
G01X1810796Y452867D02*
X1794196D01*
G01Y450567D02*
X1810796D01*
G01X1774263Y878025D02*
X1769263D01*
G01X1766263D02*
X1761263D01*
G01X1758263D02*
X1753263D01*
G01X1775763Y896525D02*
Y891525D01*
G01X1834098Y464627D02*
X1829098D01*
G01X1826487Y464619D02*
X1821487D01*
G01X1893263Y899025D02*
X1888263D01*
G01X1909263D02*
X1904263D01*
G01X1901263D02*
X1896263D01*
G01X1884900Y887385D02*
X1868300D01*
G01Y885085D02*
X1884900D01*
G54D12*
G01X814031Y1320235D02*
Y1324535D01*
X810231D01*
G01X814501Y1362741D02*
Y1367041D01*
X810701D01*
G01X814280Y1400409D02*
Y1404709D01*
X810480D01*
G54D13*
G01X304331Y1496063D02*
X322441D01*
G01X459449D02*
X477559D01*
G01X783465Y23622D02*
Y54331D01*
G01X799213Y1496063D02*
X817323D01*
G01X928098Y248031D02*
X953295D01*
G01X954331Y1496063D02*
X972441D01*
G01X1133071Y189765D02*
X1102362D01*
G01X1224409Y54331D02*
Y23622D01*
G01X1451575Y1496063D02*
X1469685D01*
G01X1606693D02*
X1624803D01*
G54D14*
G01X489037Y-206331D02*
X489911Y-205456D01*
X490566Y-203998D01*
X491003Y-201955D01*
X490566Y-200206D01*
X489693Y-199039D01*
X488164Y-198164D01*
X482269D01*
Y-215664D01*
X489474D01*
X491003Y-214498D01*
X491876Y-212747D01*
X492313Y-210706D01*
X491876Y-208664D01*
X490566Y-206914D01*
X489037Y-206331D01*
X482269D01*
G01X501734Y-215664D02*
Y-203998D01*
G01Y-206331D02*
X502826Y-205164D01*
X503918Y-204289D01*
X505446Y-203998D01*
X506537Y-204289D01*
X507848Y-205164D01*
G01X517706Y-220914D02*
X519016Y-221497D01*
X520763Y-220914D01*
X521854Y-219748D01*
X522728Y-218289D01*
X524037Y-213623D01*
X526876Y-203998D01*
G01X519889D02*
X524037Y-213623D01*
G01X543284Y-205456D02*
X541756Y-204289D01*
X540446Y-203998D01*
X538699Y-204581D01*
X537389Y-205747D01*
X536516Y-207789D01*
X536297Y-209831D01*
X536516Y-211873D01*
X537389Y-213623D01*
X538699Y-215081D01*
X540446Y-215664D01*
X541974Y-215081D01*
X543284Y-213914D01*
G01X554016Y-207789D02*
X561003D01*
X560348Y-205747D01*
X559256Y-204581D01*
X557728Y-203998D01*
X556199Y-204289D01*
X554889Y-205164D01*
X554016Y-207206D01*
X553579Y-208956D01*
Y-210706D01*
X554016Y-212456D01*
X555108Y-214206D01*
X556418Y-215372D01*
X557946Y-215664D01*
X559474Y-215081D01*
X561003Y-213331D01*
G01X597094Y-199623D02*
X595784Y-198747D01*
X594256Y-198164D01*
X592509D01*
X590544Y-199039D01*
X589016Y-200497D01*
X587924Y-202248D01*
X587051Y-205164D01*
X586832Y-207789D01*
X587269Y-210414D01*
X587924Y-212164D01*
X589234Y-213914D01*
X590763Y-215081D01*
X592291Y-215664D01*
X593819D01*
X595348Y-215081D01*
X596658Y-214206D01*
X597750Y-213040D01*
G01X613721Y-215664D02*
Y-203998D01*
G01Y-206039D02*
X612848Y-204873D01*
X611537Y-204289D01*
X610009Y-203998D01*
X608481Y-204581D01*
X607171Y-205747D01*
X606297Y-207497D01*
X605861Y-209831D01*
X606297Y-212164D01*
X607171Y-213914D01*
X608481Y-215081D01*
X610009Y-215664D01*
X611537Y-215372D01*
X612848Y-214498D01*
X613721Y-213331D01*
G01X623579Y-215664D02*
Y-203998D01*
G01Y-206914D02*
X624453Y-205456D01*
X625763Y-204289D01*
X627509Y-203998D01*
X629037Y-204289D01*
X630348Y-205456D01*
X631003Y-207497D01*
Y-215664D01*
G01X640206Y-220914D02*
X641516Y-221497D01*
X643263Y-220914D01*
X644354Y-219748D01*
X645228Y-218289D01*
X646537Y-213623D01*
X649376Y-203998D01*
G01X642389D02*
X646537Y-213623D01*
G01X662291Y-215664D02*
X660981Y-215372D01*
X659671Y-214206D01*
X658797Y-212164D01*
X658361Y-209831D01*
X658797Y-207497D01*
X659671Y-205456D01*
X660981Y-204289D01*
X662291Y-203998D01*
X663601Y-204289D01*
X664911Y-205456D01*
X665784Y-207497D01*
X666003Y-209831D01*
X665784Y-212164D01*
X664911Y-214206D01*
X663601Y-215372D01*
X662291Y-215664D01*
G01X676079D02*
Y-203998D01*
G01Y-206914D02*
X676953Y-205456D01*
X678263Y-204289D01*
X680009Y-203998D01*
X681537Y-204289D01*
X682848Y-205456D01*
X683503Y-207497D01*
Y-215664D01*
G01X710424D02*
Y-198164D01*
X715883D01*
X717629Y-199039D01*
X718721Y-200206D01*
X719158Y-202539D01*
X718721Y-204873D01*
X717411Y-206331D01*
X715883Y-207206D01*
X710424D01*
G01X715883D02*
X719158Y-215664D01*
G01X732291Y-216247D02*
X731854Y-215956D01*
Y-215372D01*
X732291Y-215081D01*
X732728Y-215372D01*
Y-215956D01*
X732291Y-216247D01*
G01X744988Y-215664D02*
Y-198164D01*
X749354D01*
X751101Y-199039D01*
X752411Y-200206D01*
X753503Y-201955D01*
X754376Y-203998D01*
X754594Y-206914D01*
X754376Y-209831D01*
X753503Y-211873D01*
X752411Y-213623D01*
X751101Y-214789D01*
X749354Y-215664D01*
X744988D01*
G01X762924D02*
Y-198164D01*
X768164D01*
X769911Y-199039D01*
X771221Y-201081D01*
X771658Y-203414D01*
X771221Y-205747D01*
X770129Y-207497D01*
X768164Y-208373D01*
X762924D01*
G01X786537Y-206331D02*
X787411Y-205456D01*
X788066Y-203998D01*
X788503Y-201955D01*
X788066Y-200206D01*
X787193Y-199039D01*
X785664Y-198164D01*
X779769D01*
Y-215664D01*
X786974D01*
X788503Y-214498D01*
X789376Y-212747D01*
X789813Y-210706D01*
X789376Y-208664D01*
X788066Y-206914D01*
X786537Y-206331D01*
X779769D01*
G01X595364Y-170664D02*
Y-153164D01*
X601041Y-167747D01*
X606718Y-153164D01*
Y-170664D01*
G01X618541D02*
X617231Y-170372D01*
X615921Y-169206D01*
X615047Y-167164D01*
X614611Y-164831D01*
X615047Y-162497D01*
X615921Y-160456D01*
X617231Y-159289D01*
X618541Y-158998D01*
X619851Y-159289D01*
X621161Y-160456D01*
X622034Y-162497D01*
X622253Y-164831D01*
X622034Y-167164D01*
X621161Y-169206D01*
X619851Y-170372D01*
X618541Y-170664D01*
G01X639971Y-153164D02*
Y-170664D01*
G01Y-168040D02*
X639098Y-169498D01*
X637787Y-170372D01*
X636259Y-170664D01*
X634513Y-170081D01*
X633203Y-168623D01*
X632329Y-166873D01*
X632111Y-164831D01*
X632329Y-162789D01*
X633203Y-161039D01*
X634513Y-159581D01*
X636259Y-158998D01*
X637787Y-159289D01*
X638879Y-159873D01*
X639971Y-161039D01*
G01X650266Y-162789D02*
X657253D01*
X656598Y-160747D01*
X655506Y-159581D01*
X653978Y-158998D01*
X652449Y-159289D01*
X651139Y-160164D01*
X650266Y-162206D01*
X649829Y-163956D01*
Y-165706D01*
X650266Y-167456D01*
X651358Y-169206D01*
X652668Y-170372D01*
X654196Y-170664D01*
X655724Y-170081D01*
X657253Y-168331D01*
G01X671041Y-170664D02*
Y-153164D01*
G01X839441Y-215664D02*
Y-198164D01*
X836821Y-201664D01*
G01Y-215664D02*
X842061D01*
G01X852793Y-208373D02*
X854321Y-206331D01*
X855631Y-205164D01*
X857378Y-204581D01*
X858906Y-205164D01*
X859998Y-206331D01*
X860871Y-208081D01*
X861089Y-210122D01*
X860871Y-211873D01*
X859998Y-213623D01*
X858687Y-215081D01*
X857159Y-215664D01*
X855413Y-215081D01*
X853884Y-213331D01*
X853011Y-210706D01*
X852793Y-207789D01*
X853229Y-203998D01*
X853884Y-201955D01*
X854976Y-199914D01*
X856504Y-198456D01*
X858033Y-198164D01*
X859561Y-198747D01*
X860653Y-200206D01*
G01X869638Y-212164D02*
X870947Y-214206D01*
X872694Y-215372D01*
X874659Y-215664D01*
X876406Y-215372D01*
X878153Y-213914D01*
X879244Y-212164D01*
X879463Y-210414D01*
X879026Y-208373D01*
X877498Y-206914D01*
X875969Y-206331D01*
X874004D01*
G01X875969D02*
X877279Y-205456D01*
X878371Y-203998D01*
X878808Y-202248D01*
X878371Y-200497D01*
X877279Y-199039D01*
X875314Y-198164D01*
X873349Y-198456D01*
X871384Y-199623D01*
G01X891941Y-215664D02*
Y-198164D01*
X889321Y-201664D01*
G01Y-215664D02*
X894561D01*
G01X909004D02*
X909441Y-211873D01*
X910096Y-208664D01*
X910969Y-205747D01*
X912061Y-202539D01*
X913808Y-198164D01*
X905074D01*
G01X826324Y-170664D02*
Y-153164D01*
X831564D01*
X833311Y-154039D01*
X834621Y-156081D01*
X835058Y-158414D01*
X834621Y-160747D01*
X833529Y-162497D01*
X831564Y-163373D01*
X826324D01*
G01X852994Y-154623D02*
X851684Y-153747D01*
X850156Y-153164D01*
X848409D01*
X846444Y-154039D01*
X844916Y-155497D01*
X843824Y-157248D01*
X842951Y-160164D01*
X842732Y-162789D01*
X843169Y-165414D01*
X843824Y-167164D01*
X845134Y-168914D01*
X846663Y-170081D01*
X848191Y-170664D01*
X849719D01*
X851248Y-170081D01*
X852558Y-169206D01*
X853650Y-168040D01*
G01X867437Y-161331D02*
X868311Y-160456D01*
X868966Y-158998D01*
X869403Y-156955D01*
X868966Y-155206D01*
X868093Y-154039D01*
X866564Y-153164D01*
X860669D01*
Y-170664D01*
X867874D01*
X869403Y-169498D01*
X870276Y-167747D01*
X870713Y-165706D01*
X870276Y-163664D01*
X868966Y-161914D01*
X867437Y-161331D01*
X860669D01*
G01X876641Y-176497D02*
X889741D01*
G01X895669Y-170664D02*
Y-153164D01*
X905713Y-170664D01*
Y-153164D01*
G01X918191Y-170664D02*
X916444Y-170372D01*
X914916Y-169206D01*
X913606Y-167456D01*
X912732Y-165414D01*
X912296Y-163081D01*
Y-160747D01*
X912732Y-158414D01*
X913606Y-156372D01*
X914916Y-154623D01*
X916444Y-153456D01*
X918191Y-153164D01*
X919937Y-153456D01*
X921466Y-154623D01*
X922776Y-156372D01*
X923650Y-158414D01*
X924086Y-160747D01*
Y-163081D01*
X923650Y-165414D01*
X922776Y-167456D01*
X921466Y-169206D01*
X919937Y-170372D01*
X918191Y-170664D01*
G01X1000741Y-215664D02*
Y-198164D01*
X998121Y-201664D01*
G01Y-215664D02*
X1003361D01*
G01X969032Y-153164D02*
X974491Y-170664D01*
X979950Y-153164D01*
G01X996358Y-170664D02*
X987624D01*
Y-153164D01*
X996358D01*
G01X992864Y-161622D02*
X987624D01*
G01X1005124Y-170664D02*
Y-153164D01*
X1010583D01*
X1012329Y-154039D01*
X1013421Y-155206D01*
X1013858Y-157539D01*
X1013421Y-159873D01*
X1012111Y-161331D01*
X1010583Y-162206D01*
X1005124D01*
G01X1010583D02*
X1013858Y-170664D01*
G01X1026991Y-171247D02*
X1026554Y-170956D01*
Y-170372D01*
X1026991Y-170081D01*
X1027428Y-170372D01*
Y-170956D01*
X1026991Y-171247D01*
G01X1175195Y-206331D02*
X1174321Y-205456D01*
X1173666Y-203998D01*
X1173229Y-201955D01*
X1173666Y-200206D01*
X1174539Y-199039D01*
X1176068Y-198164D01*
X1181963D01*
Y-215664D01*
X1174758D01*
X1173229Y-214498D01*
X1172356Y-212747D01*
X1171919Y-210706D01*
X1172356Y-208664D01*
X1173666Y-206914D01*
X1175195Y-206331D01*
X1181963D01*
G01X1164026Y-213331D02*
X1162279Y-214789D01*
X1160314Y-215664D01*
X1158568D01*
X1156821Y-214789D01*
X1155511Y-213331D01*
X1154856Y-211289D01*
X1155293Y-209248D01*
X1156384Y-207497D01*
X1158349Y-206331D01*
X1160969Y-205747D01*
X1162498Y-204581D01*
X1163153Y-202539D01*
X1162716Y-200497D01*
X1161624Y-199039D01*
X1160096Y-198164D01*
X1158568D01*
X1157039Y-198747D01*
X1155729Y-200206D01*
G01X1144561Y-198164D02*
X1139321D01*
G01X1141941D02*
Y-215664D01*
G01X1144561D02*
X1139321D01*
G01X1128808Y-198164D02*
Y-215664D01*
X1120074D01*
G01X1111744D02*
Y-198164D01*
G01X1103448D02*
X1111744Y-208956D01*
G01X1102138Y-215664D02*
X1108033Y-203998D01*
G01X1102574Y-153164D02*
Y-170664D01*
X1111308D01*
G01X1128371D02*
Y-158998D01*
G01Y-161039D02*
X1127498Y-159873D01*
X1126187Y-159289D01*
X1124659Y-158998D01*
X1123131Y-159581D01*
X1121821Y-160747D01*
X1120947Y-162497D01*
X1120511Y-164831D01*
X1120947Y-167164D01*
X1121821Y-168914D01*
X1123131Y-170081D01*
X1124659Y-170664D01*
X1126187Y-170372D01*
X1127498Y-169498D01*
X1128371Y-168331D01*
G01X1137356Y-175914D02*
X1138666Y-176497D01*
X1140413Y-175914D01*
X1141504Y-174748D01*
X1142378Y-173289D01*
X1143687Y-168623D01*
X1146526Y-158998D01*
G01X1139539D02*
X1143687Y-168623D01*
G01X1156166Y-162789D02*
X1163153D01*
X1162498Y-160747D01*
X1161406Y-159581D01*
X1159878Y-158998D01*
X1158349Y-159289D01*
X1157039Y-160164D01*
X1156166Y-162206D01*
X1155729Y-163956D01*
Y-165706D01*
X1156166Y-167456D01*
X1157258Y-169206D01*
X1158568Y-170372D01*
X1160096Y-170664D01*
X1161624Y-170081D01*
X1163153Y-168331D01*
G01X1173884Y-170664D02*
Y-158998D01*
G01Y-161331D02*
X1174976Y-160164D01*
X1176068Y-159289D01*
X1177596Y-158998D01*
X1178687Y-159289D01*
X1179998Y-160164D01*
G01X1244688Y-170664D02*
Y-153164D01*
X1249054D01*
X1250801Y-154039D01*
X1252111Y-155206D01*
X1253203Y-156955D01*
X1254076Y-158998D01*
X1254294Y-161914D01*
X1254076Y-164831D01*
X1253203Y-166873D01*
X1252111Y-168623D01*
X1250801Y-169789D01*
X1249054Y-170664D01*
X1244688D01*
G01X1263716Y-162789D02*
X1270703D01*
X1270048Y-160747D01*
X1268956Y-159581D01*
X1267428Y-158998D01*
X1265899Y-159289D01*
X1264589Y-160164D01*
X1263716Y-162206D01*
X1263279Y-163956D01*
Y-165706D01*
X1263716Y-167456D01*
X1264808Y-169206D01*
X1266118Y-170372D01*
X1267646Y-170664D01*
X1269174Y-170081D01*
X1270703Y-168331D01*
G01X1281216Y-168623D02*
X1282308Y-169789D01*
X1283836Y-170664D01*
X1285146D01*
X1286456Y-170081D01*
X1287329Y-169206D01*
X1287766Y-168040D01*
X1287548Y-166289D01*
X1286674Y-165414D01*
X1282744Y-163664D01*
X1281871Y-161622D01*
X1282308Y-160164D01*
X1283181Y-159289D01*
X1284491Y-158998D01*
X1285801Y-159289D01*
X1287111Y-160164D01*
G01X1301991Y-158998D02*
Y-170664D01*
G01Y-154331D02*
X1301554Y-154039D01*
Y-153456D01*
X1301991Y-153164D01*
X1302428Y-153456D01*
Y-154039D01*
X1301991Y-154331D01*
G01X1316434Y-175039D02*
X1317963Y-176206D01*
X1319709Y-176497D01*
X1321237Y-176206D01*
X1322548Y-174748D01*
X1323421Y-172706D01*
Y-158998D01*
G01Y-161331D02*
X1322548Y-160164D01*
X1321237Y-159289D01*
X1319709Y-158998D01*
X1317963Y-159581D01*
X1316871Y-160747D01*
X1315997Y-162789D01*
X1315561Y-164831D01*
X1315779Y-166581D01*
X1316653Y-168623D01*
X1317963Y-170081D01*
X1319709Y-170664D01*
X1321019Y-170372D01*
X1322548Y-169206D01*
X1323421Y-168040D01*
G01X1333279Y-170664D02*
Y-158998D01*
G01Y-161914D02*
X1334153Y-160456D01*
X1335463Y-159289D01*
X1337209Y-158998D01*
X1338737Y-159289D01*
X1340048Y-160456D01*
X1340703Y-162497D01*
Y-170664D01*
G01X1351216Y-162789D02*
X1358203D01*
X1357548Y-160747D01*
X1356456Y-159581D01*
X1354928Y-158998D01*
X1353399Y-159289D01*
X1352089Y-160164D01*
X1351216Y-162206D01*
X1350779Y-163956D01*
Y-165706D01*
X1351216Y-167456D01*
X1352308Y-169206D01*
X1353618Y-170372D01*
X1355146Y-170664D01*
X1356674Y-170081D01*
X1358203Y-168331D01*
G01X1368934Y-170664D02*
Y-158998D01*
G01Y-161331D02*
X1370026Y-160164D01*
X1371118Y-159289D01*
X1372646Y-158998D01*
X1373737Y-159289D01*
X1375048Y-160164D01*
G01X1266991Y-215664D02*
X1265244Y-215372D01*
X1263716Y-214206D01*
X1262406Y-212456D01*
X1261532Y-210414D01*
X1261096Y-208081D01*
Y-205747D01*
X1261532Y-203414D01*
X1262406Y-201372D01*
X1263716Y-199623D01*
X1265244Y-198456D01*
X1266991Y-198164D01*
X1268737Y-198456D01*
X1270266Y-199623D01*
X1271576Y-201372D01*
X1272450Y-203414D01*
X1272886Y-205747D01*
Y-208081D01*
X1272450Y-210414D01*
X1271576Y-212456D01*
X1270266Y-214206D01*
X1268737Y-215372D01*
X1266991Y-215664D01*
G01X1268737Y-210997D02*
X1271358Y-215664D01*
G01X1279688Y-198164D02*
Y-210706D01*
X1280561Y-213331D01*
X1282308Y-215081D01*
X1284491Y-215664D01*
X1286674Y-215081D01*
X1288421Y-213331D01*
X1289294Y-210706D01*
Y-198164D01*
G01X1299371D02*
X1304611D01*
G01X1301991D02*
Y-215664D01*
G01X1299371D02*
X1304611D01*
G01X1314469D02*
Y-198164D01*
X1324513Y-215664D01*
Y-198164D01*
G01X1341794Y-199623D02*
X1340484Y-198747D01*
X1338956Y-198164D01*
X1337209D01*
X1335244Y-199039D01*
X1333716Y-200497D01*
X1332624Y-202248D01*
X1331751Y-205164D01*
X1331532Y-207789D01*
X1331969Y-210414D01*
X1332624Y-212164D01*
X1333934Y-213914D01*
X1335463Y-215081D01*
X1336991Y-215664D01*
X1338519D01*
X1340048Y-215081D01*
X1341358Y-214206D01*
X1342450Y-213040D01*
G01X1354491Y-215664D02*
Y-207789D01*
X1350124Y-198164D01*
G01X1358858D02*
X1354491Y-207789D01*
G01X1415691Y-198164D02*
X1413944Y-198747D01*
X1412634Y-200206D01*
X1411761Y-201955D01*
X1411106Y-204289D01*
X1410888Y-206914D01*
X1411106Y-209539D01*
X1411761Y-211873D01*
X1412634Y-213623D01*
X1413944Y-215081D01*
X1415691Y-215664D01*
X1417437Y-215081D01*
X1418748Y-213623D01*
X1419621Y-211873D01*
X1420276Y-209539D01*
X1420494Y-206914D01*
X1420276Y-204289D01*
X1419621Y-201955D01*
X1418748Y-200206D01*
X1417437Y-198747D01*
X1415691Y-198164D01*
G01X1429043Y-208373D02*
X1430571Y-206331D01*
X1431881Y-205164D01*
X1433628Y-204581D01*
X1435156Y-205164D01*
X1436248Y-206331D01*
X1437121Y-208081D01*
X1437339Y-210122D01*
X1437121Y-211873D01*
X1436248Y-213623D01*
X1434937Y-215081D01*
X1433409Y-215664D01*
X1431663Y-215081D01*
X1430134Y-213331D01*
X1429261Y-210706D01*
X1429043Y-207789D01*
X1429479Y-203998D01*
X1430134Y-201955D01*
X1431226Y-199914D01*
X1432754Y-198456D01*
X1434283Y-198164D01*
X1435811Y-198747D01*
X1436903Y-200206D01*
G01X1446761Y-216247D02*
X1454621Y-198164D01*
G01X1468191D02*
X1466444Y-198747D01*
X1465134Y-200206D01*
X1464261Y-201955D01*
X1463606Y-204289D01*
X1463388Y-206914D01*
X1463606Y-209539D01*
X1464261Y-211873D01*
X1465134Y-213623D01*
X1466444Y-215081D01*
X1468191Y-215664D01*
X1469937Y-215081D01*
X1471248Y-213623D01*
X1472121Y-211873D01*
X1472776Y-209539D01*
X1472994Y-206914D01*
X1472776Y-204289D01*
X1472121Y-201955D01*
X1471248Y-200206D01*
X1469937Y-198747D01*
X1468191Y-198164D01*
G01X1481979Y-213623D02*
X1483508Y-215081D01*
X1485254Y-215664D01*
X1487001Y-215081D01*
X1488529Y-213331D01*
X1489621Y-210706D01*
X1490058Y-208081D01*
Y-204873D01*
X1489621Y-202248D01*
X1488529Y-199914D01*
X1487219Y-198747D01*
X1485691Y-198164D01*
X1483944Y-198747D01*
X1482634Y-199914D01*
X1481761Y-201664D01*
X1481324Y-203998D01*
X1481761Y-206039D01*
X1482853Y-208081D01*
X1484163Y-209248D01*
X1485691Y-209539D01*
X1487437Y-208956D01*
X1488748Y-207497D01*
X1490058Y-204873D01*
G01X1499261Y-216247D02*
X1507121Y-198164D01*
G01X1516543Y-201081D02*
X1517853Y-199331D01*
X1519381Y-198456D01*
X1521128Y-198164D01*
X1523311Y-198747D01*
X1524839Y-200206D01*
X1525276Y-201955D01*
X1525058Y-203706D01*
X1524184Y-205164D01*
X1519818Y-208081D01*
X1517853Y-210122D01*
X1516543Y-213040D01*
X1516106Y-215664D01*
X1525276D01*
G01X1538191Y-198164D02*
X1536444Y-198747D01*
X1535134Y-200206D01*
X1534261Y-201955D01*
X1533606Y-204289D01*
X1533388Y-206914D01*
X1533606Y-209539D01*
X1534261Y-211873D01*
X1535134Y-213623D01*
X1536444Y-215081D01*
X1538191Y-215664D01*
X1539937Y-215081D01*
X1541248Y-213623D01*
X1542121Y-211873D01*
X1542776Y-209539D01*
X1542994Y-206914D01*
X1542776Y-204289D01*
X1542121Y-201955D01*
X1541248Y-200206D01*
X1539937Y-198747D01*
X1538191Y-198164D01*
G01X1555691Y-215664D02*
Y-198164D01*
X1553071Y-201664D01*
G01Y-215664D02*
X1558311D01*
G01X1572754D02*
X1573191Y-211873D01*
X1573846Y-208664D01*
X1574719Y-205747D01*
X1575811Y-202539D01*
X1577558Y-198164D01*
X1568824D01*
G01X1463388Y-170664D02*
Y-153164D01*
X1467754D01*
X1469501Y-154039D01*
X1470811Y-155206D01*
X1471903Y-156955D01*
X1472776Y-158998D01*
X1472994Y-161914D01*
X1472776Y-164831D01*
X1471903Y-166873D01*
X1470811Y-168623D01*
X1469501Y-169789D01*
X1467754Y-170664D01*
X1463388D01*
G01X1489621D02*
Y-158998D01*
G01Y-161039D02*
X1488748Y-159873D01*
X1487437Y-159289D01*
X1485909Y-158998D01*
X1484381Y-159581D01*
X1483071Y-160747D01*
X1482197Y-162497D01*
X1481761Y-164831D01*
X1482197Y-167164D01*
X1483071Y-168914D01*
X1484381Y-170081D01*
X1485909Y-170664D01*
X1487437Y-170372D01*
X1488748Y-169498D01*
X1489621Y-168331D01*
G01X1503191Y-153164D02*
Y-170664D01*
G01X1500134Y-158998D02*
X1506248D01*
G01X1517416Y-162789D02*
X1524403D01*
X1523748Y-160747D01*
X1522656Y-159581D01*
X1521128Y-158998D01*
X1519599Y-159289D01*
X1518289Y-160164D01*
X1517416Y-162206D01*
X1516979Y-163956D01*
Y-165706D01*
X1517416Y-167456D01*
X1518508Y-169206D01*
X1519818Y-170372D01*
X1521346Y-170664D01*
X1522874Y-170081D01*
X1524403Y-168331D01*
G01X63792Y863767D02*
X63917Y863517D01*
X64000Y863225D01*
Y862892D01*
X63875Y862517D01*
X63667Y862225D01*
X63417Y862017D01*
X63000Y861850D01*
X62625Y861808D01*
X62250Y861892D01*
X62000Y862017D01*
X61750Y862267D01*
X61583Y862558D01*
X61500Y862850D01*
Y863142D01*
X61583Y863433D01*
X61708Y863683D01*
X61875Y863892D01*
G01X62542Y865158D02*
X62833Y865450D01*
X63000Y865700D01*
X63083Y866033D01*
X63000Y866325D01*
X62833Y866533D01*
X62583Y866700D01*
X62292Y866742D01*
X62042Y866700D01*
X61792Y866533D01*
X61583Y866283D01*
X61500Y865992D01*
X61583Y865658D01*
X61833Y865367D01*
X62208Y865200D01*
X62625Y865158D01*
X63167Y865242D01*
X63458Y865367D01*
X63750Y865575D01*
X63958Y865867D01*
X64000Y866158D01*
X63917Y866450D01*
X63708Y866658D01*
G01X63583Y868258D02*
X63833Y868508D01*
X63958Y868800D01*
X64000Y869133D01*
X63917Y869550D01*
X63708Y869842D01*
X63458Y869925D01*
X63208Y869883D01*
X63000Y869717D01*
X62583Y868883D01*
X62292Y868508D01*
X61875Y868258D01*
X61500Y868175D01*
Y869925D01*
G01X64000Y872150D02*
X63917Y871817D01*
X63708Y871567D01*
X63458Y871400D01*
X63125Y871275D01*
X62750Y871233D01*
X62375Y871275D01*
X62042Y871400D01*
X61792Y871567D01*
X61583Y871817D01*
X61500Y872150D01*
X61583Y872483D01*
X61792Y872733D01*
X62042Y872900D01*
X62375Y873025D01*
X62750Y873067D01*
X63125Y873025D01*
X63458Y872900D01*
X63708Y872733D01*
X63917Y872483D01*
X64000Y872150D01*
G01X98833Y924792D02*
X99083Y924917D01*
X99375Y925000D01*
X99708D01*
X100083Y924875D01*
X100375Y924667D01*
X100583Y924417D01*
X100750Y924000D01*
X100792Y923625D01*
X100708Y923250D01*
X100583Y923000D01*
X100333Y922750D01*
X100042Y922583D01*
X99750Y922500D01*
X99458D01*
X99167Y922583D01*
X98917Y922708D01*
X98708Y922875D01*
G01X97442Y923542D02*
X97150Y923833D01*
X96900Y924000D01*
X96567Y924083D01*
X96275Y924000D01*
X96067Y923833D01*
X95900Y923583D01*
X95858Y923292D01*
X95900Y923042D01*
X96067Y922792D01*
X96317Y922583D01*
X96608Y922500D01*
X96942Y922583D01*
X97233Y922833D01*
X97400Y923208D01*
X97442Y923625D01*
X97358Y924167D01*
X97233Y924458D01*
X97025Y924750D01*
X96733Y924958D01*
X96442Y925000D01*
X96150Y924917D01*
X95942Y924708D01*
G01X94467Y923000D02*
X94217Y922708D01*
X93883Y922542D01*
X93508Y922500D01*
X93175Y922542D01*
X92842Y922750D01*
X92633Y923000D01*
X92592Y923250D01*
X92675Y923542D01*
X92967Y923750D01*
X93258Y923833D01*
X93633D01*
G01X93258D02*
X93008Y923958D01*
X92800Y924167D01*
X92717Y924417D01*
X92800Y924667D01*
X93008Y924875D01*
X93383Y925000D01*
X93758Y924958D01*
X94133Y924792D01*
G01X90450Y925000D02*
X90783Y924917D01*
X91033Y924708D01*
X91200Y924458D01*
X91325Y924125D01*
X91367Y923750D01*
X91325Y923375D01*
X91200Y923042D01*
X91033Y922792D01*
X90783Y922583D01*
X90450Y922500D01*
X90117Y922583D01*
X89867Y922792D01*
X89700Y923042D01*
X89575Y923375D01*
X89533Y923750D01*
X89575Y924125D01*
X89700Y924458D01*
X89867Y924708D01*
X90117Y924917D01*
X90450Y925000D01*
G01X81300Y913367D02*
X83800D01*
Y914408D01*
X83675Y914742D01*
X83508Y914950D01*
X83175Y915033D01*
X82842Y914950D01*
X82633Y914700D01*
X82508Y914408D01*
Y913367D01*
G01Y914408D02*
X81300Y915033D01*
G01Y917300D02*
X83800D01*
X83300Y916800D01*
G01X81300D02*
Y917800D01*
G01Y920400D02*
X83800D01*
X83300Y919900D01*
G01X81300D02*
Y920900D01*
G01Y923500D02*
X83800D01*
X83300Y923000D01*
G01X81300D02*
Y924000D01*
G01X81800Y925683D02*
X81508Y925933D01*
X81342Y926267D01*
X81300Y926642D01*
X81342Y926975D01*
X81550Y927308D01*
X81800Y927517D01*
X82050Y927558D01*
X82342Y927475D01*
X82550Y927183D01*
X82633Y926892D01*
Y926517D01*
G01Y926892D02*
X82758Y927142D01*
X82967Y927350D01*
X83217Y927433D01*
X83467Y927350D01*
X83675Y927142D01*
X83800Y926767D01*
X83758Y926392D01*
X83592Y926017D01*
G01X90941Y900016D02*
X86941D01*
Y907416D01*
G01X100233Y917900D02*
Y920400D01*
X99192D01*
X98858Y920275D01*
X98650Y920108D01*
X98567Y919775D01*
X98650Y919442D01*
X98900Y919233D01*
X99192Y919108D01*
X100233D01*
G01X99192D02*
X98567Y917900D01*
G01X96300D02*
Y920400D01*
X96800Y919900D01*
G01Y917900D02*
X95800D01*
G01X93200D02*
Y920400D01*
X93700Y919900D01*
G01Y917900D02*
X92700D01*
G01X90100Y920400D02*
X90433Y920317D01*
X90683Y920108D01*
X90850Y919858D01*
X90975Y919525D01*
X91017Y919150D01*
X90975Y918775D01*
X90850Y918442D01*
X90683Y918192D01*
X90433Y917983D01*
X90100Y917900D01*
X89767Y917983D01*
X89517Y918192D01*
X89350Y918442D01*
X89225Y918775D01*
X89183Y919150D01*
X89225Y919525D01*
X89350Y919858D01*
X89517Y920108D01*
X89767Y920317D01*
X90100Y920400D01*
G01X87708Y918192D02*
X87417Y917983D01*
X87083Y917900D01*
X86750Y917983D01*
X86458Y918233D01*
X86250Y918608D01*
X86167Y918983D01*
Y919442D01*
X86250Y919817D01*
X86458Y920150D01*
X86708Y920317D01*
X87000Y920400D01*
X87333Y920317D01*
X87583Y920150D01*
X87750Y919900D01*
X87833Y919567D01*
X87750Y919275D01*
X87542Y918983D01*
X87292Y918817D01*
X87000Y918775D01*
X86667Y918858D01*
X86417Y919067D01*
X86167Y919442D01*
G01X92600Y902300D02*
Y906300D01*
X100000D01*
G01X64733Y901792D02*
X64983Y901917D01*
X65275Y902000D01*
X65608D01*
X65983Y901875D01*
X66275Y901667D01*
X66483Y901417D01*
X66650Y901000D01*
X66692Y900625D01*
X66608Y900250D01*
X66483Y900000D01*
X66233Y899750D01*
X65942Y899583D01*
X65650Y899500D01*
X65358D01*
X65067Y899583D01*
X64817Y899708D01*
X64608Y899875D01*
G01X63342Y900542D02*
X63050Y900833D01*
X62800Y901000D01*
X62467Y901083D01*
X62175Y901000D01*
X61967Y900833D01*
X61800Y900583D01*
X61758Y900292D01*
X61800Y900042D01*
X61967Y899792D01*
X62217Y899583D01*
X62508Y899500D01*
X62842Y899583D01*
X63133Y899833D01*
X63300Y900208D01*
X63342Y900625D01*
X63258Y901167D01*
X63133Y901458D01*
X62925Y901750D01*
X62633Y901958D01*
X62342Y902000D01*
X62050Y901917D01*
X61842Y901708D01*
G01X60242Y901583D02*
X59992Y901833D01*
X59700Y901958D01*
X59367Y902000D01*
X58950Y901917D01*
X58658Y901708D01*
X58575Y901458D01*
X58617Y901208D01*
X58783Y901000D01*
X59617Y900583D01*
X59992Y900292D01*
X60242Y899875D01*
X60325Y899500D01*
X58575D01*
G01X56350D02*
X56058Y899542D01*
X55725Y899667D01*
X55517Y899875D01*
X55433Y900167D01*
X55517Y900458D01*
X55767Y900708D01*
X56142Y900833D01*
X56558D01*
X56808Y900917D01*
X57017Y901125D01*
X57100Y901417D01*
X56975Y901708D01*
X56683Y901917D01*
X56350Y902000D01*
X56017Y901917D01*
X55725Y901708D01*
X55600Y901417D01*
X55683Y901125D01*
X55892Y900917D01*
X56142Y900833D01*
X56558D01*
X56933Y900708D01*
X57183Y900458D01*
X57267Y900167D01*
X57183Y899875D01*
X56975Y899667D01*
X56642Y899542D01*
X56350Y899500D01*
G01X32500Y882967D02*
X35000D01*
Y884008D01*
X34875Y884342D01*
X34708Y884550D01*
X34375Y884633D01*
X34042Y884550D01*
X33833Y884300D01*
X33708Y884008D01*
Y882967D01*
G01Y884008D02*
X32500Y884633D01*
G01Y886900D02*
X35000D01*
X34500Y886400D01*
G01X32500D02*
Y887400D01*
G01X35000Y890000D02*
X34917Y889667D01*
X34708Y889417D01*
X34458Y889250D01*
X34125Y889125D01*
X33750Y889083D01*
X33375Y889125D01*
X33042Y889250D01*
X32792Y889417D01*
X32583Y889667D01*
X32500Y890000D01*
X32583Y890333D01*
X32792Y890583D01*
X33042Y890750D01*
X33375Y890875D01*
X33750Y890917D01*
X34125Y890875D01*
X34458Y890750D01*
X34708Y890583D01*
X34917Y890333D01*
X35000Y890000D01*
G01X32792Y892392D02*
X32583Y892683D01*
X32500Y893017D01*
X32583Y893350D01*
X32833Y893642D01*
X33208Y893850D01*
X33583Y893933D01*
X34042D01*
X34417Y893850D01*
X34750Y893642D01*
X34917Y893392D01*
X35000Y893100D01*
X34917Y892767D01*
X34750Y892517D01*
X34500Y892350D01*
X34167Y892267D01*
X33875Y892350D01*
X33583Y892558D01*
X33417Y892808D01*
X33375Y893100D01*
X33458Y893433D01*
X33667Y893683D01*
X34042Y893933D01*
G01X32500Y896200D02*
X32542Y896492D01*
X32667Y896825D01*
X32875Y897033D01*
X33167Y897117D01*
X33458Y897033D01*
X33708Y896783D01*
X33833Y896408D01*
Y895992D01*
X33917Y895742D01*
X34125Y895533D01*
X34417Y895450D01*
X34708Y895575D01*
X34917Y895867D01*
X35000Y896200D01*
X34917Y896533D01*
X34708Y896825D01*
X34417Y896950D01*
X34125Y896867D01*
X33917Y896658D01*
X33833Y896408D01*
Y895992D01*
X33708Y895617D01*
X33458Y895367D01*
X33167Y895283D01*
X32875Y895367D01*
X32667Y895575D01*
X32542Y895908D01*
X32500Y896200D01*
G01X56792Y860267D02*
X56917Y860017D01*
X57000Y859725D01*
Y859392D01*
X56875Y859017D01*
X56667Y858725D01*
X56417Y858517D01*
X56000Y858350D01*
X55625Y858308D01*
X55250Y858392D01*
X55000Y858517D01*
X54750Y858767D01*
X54583Y859058D01*
X54500Y859350D01*
Y859642D01*
X54583Y859933D01*
X54708Y860183D01*
X54875Y860392D01*
G01X55542Y861658D02*
X55833Y861950D01*
X56000Y862200D01*
X56083Y862533D01*
X56000Y862825D01*
X55833Y863033D01*
X55583Y863200D01*
X55292Y863242D01*
X55042Y863200D01*
X54792Y863033D01*
X54583Y862783D01*
X54500Y862492D01*
X54583Y862158D01*
X54833Y861867D01*
X55208Y861700D01*
X55625Y861658D01*
X56167Y861742D01*
X56458Y861867D01*
X56750Y862075D01*
X56958Y862367D01*
X57000Y862658D01*
X56917Y862950D01*
X56708Y863158D01*
G01X54500Y865550D02*
X57000D01*
X56500Y865050D01*
G01X54500D02*
Y866050D01*
G01Y868567D02*
X55042Y868650D01*
X55500Y868775D01*
X55917Y868942D01*
X56375Y869150D01*
X57000Y869483D01*
Y867817D01*
G01X49792Y860267D02*
X49917Y860017D01*
X50000Y859725D01*
Y859392D01*
X49875Y859017D01*
X49667Y858725D01*
X49417Y858517D01*
X49000Y858350D01*
X48625Y858308D01*
X48250Y858392D01*
X48000Y858517D01*
X47750Y858767D01*
X47583Y859058D01*
X47500Y859350D01*
Y859642D01*
X47583Y859933D01*
X47708Y860183D01*
X47875Y860392D01*
G01X48542Y861658D02*
X48833Y861950D01*
X49000Y862200D01*
X49083Y862533D01*
X49000Y862825D01*
X48833Y863033D01*
X48583Y863200D01*
X48292Y863242D01*
X48042Y863200D01*
X47792Y863033D01*
X47583Y862783D01*
X47500Y862492D01*
X47583Y862158D01*
X47833Y861867D01*
X48208Y861700D01*
X48625Y861658D01*
X49167Y861742D01*
X49458Y861867D01*
X49750Y862075D01*
X49958Y862367D01*
X50000Y862658D01*
X49917Y862950D01*
X49708Y863158D01*
G01X47500Y865550D02*
X50000D01*
X49500Y865050D01*
G01X47500D02*
Y866050D01*
G01Y868650D02*
X47542Y868942D01*
X47667Y869275D01*
X47875Y869483D01*
X48167Y869567D01*
X48458Y869483D01*
X48708Y869233D01*
X48833Y868858D01*
Y868442D01*
X48917Y868192D01*
X49125Y867983D01*
X49417Y867900D01*
X49708Y868025D01*
X49917Y868317D01*
X50000Y868650D01*
X49917Y868983D01*
X49708Y869275D01*
X49417Y869400D01*
X49125Y869317D01*
X48917Y869108D01*
X48833Y868858D01*
Y868442D01*
X48708Y868067D01*
X48458Y867817D01*
X48167Y867733D01*
X47875Y867817D01*
X47667Y868025D01*
X47542Y868358D01*
X47500Y868650D01*
G01X42292Y890767D02*
X42417Y890517D01*
X42500Y890225D01*
Y889892D01*
X42375Y889517D01*
X42167Y889225D01*
X41917Y889017D01*
X41500Y888850D01*
X41125Y888808D01*
X40750Y888892D01*
X40500Y889017D01*
X40250Y889267D01*
X40083Y889558D01*
X40000Y889850D01*
Y890142D01*
X40083Y890433D01*
X40208Y890683D01*
X40375Y890892D01*
G01X41042Y892158D02*
X41333Y892450D01*
X41500Y892700D01*
X41583Y893033D01*
X41500Y893325D01*
X41333Y893533D01*
X41083Y893700D01*
X40792Y893742D01*
X40542Y893700D01*
X40292Y893533D01*
X40083Y893283D01*
X40000Y892992D01*
X40083Y892658D01*
X40333Y892367D01*
X40708Y892200D01*
X41125Y892158D01*
X41667Y892242D01*
X41958Y892367D01*
X42250Y892575D01*
X42458Y892867D01*
X42500Y893158D01*
X42417Y893450D01*
X42208Y893658D01*
G01X40000Y896050D02*
X42500D01*
X42000Y895550D01*
G01X40000D02*
Y896550D01*
G01X40292Y898442D02*
X40083Y898733D01*
X40000Y899067D01*
X40083Y899400D01*
X40333Y899692D01*
X40708Y899900D01*
X41083Y899983D01*
X41542D01*
X41917Y899900D01*
X42250Y899692D01*
X42417Y899442D01*
X42500Y899150D01*
X42417Y898817D01*
X42250Y898567D01*
X42000Y898400D01*
X41667Y898317D01*
X41375Y898400D01*
X41083Y898608D01*
X40917Y898858D01*
X40875Y899150D01*
X40958Y899483D01*
X41167Y899733D01*
X41542Y899983D01*
G01X65233Y906792D02*
X65483Y906917D01*
X65775Y907000D01*
X66108D01*
X66483Y906875D01*
X66775Y906667D01*
X66983Y906417D01*
X67150Y906000D01*
X67192Y905625D01*
X67108Y905250D01*
X66983Y905000D01*
X66733Y904750D01*
X66442Y904583D01*
X66150Y904500D01*
X65858D01*
X65567Y904583D01*
X65317Y904708D01*
X65108Y904875D01*
G01X63842Y905542D02*
X63550Y905833D01*
X63300Y906000D01*
X62967Y906083D01*
X62675Y906000D01*
X62467Y905833D01*
X62300Y905583D01*
X62258Y905292D01*
X62300Y905042D01*
X62467Y904792D01*
X62717Y904583D01*
X63008Y904500D01*
X63342Y904583D01*
X63633Y904833D01*
X63800Y905208D01*
X63842Y905625D01*
X63758Y906167D01*
X63633Y906458D01*
X63425Y906750D01*
X63133Y906958D01*
X62842Y907000D01*
X62550Y906917D01*
X62342Y906708D01*
G01X60742Y906583D02*
X60492Y906833D01*
X60200Y906958D01*
X59867Y907000D01*
X59450Y906917D01*
X59158Y906708D01*
X59075Y906458D01*
X59117Y906208D01*
X59283Y906000D01*
X60117Y905583D01*
X60492Y905292D01*
X60742Y904875D01*
X60825Y904500D01*
X59075D01*
G01X56350D02*
Y907000D01*
X57892Y905208D01*
X55808D01*
G01X77600Y915150D02*
X76767D01*
Y914400D01*
X77017Y914150D01*
X77308Y913983D01*
X77725Y913900D01*
X78142Y913983D01*
X78433Y914150D01*
X78683Y914400D01*
X78850Y914692D01*
X78933Y915025D01*
Y915317D01*
X78850Y915567D01*
X78683Y915858D01*
X78433Y916108D01*
X78183Y916275D01*
X77850Y916400D01*
X77558D01*
X77225Y916317D01*
X76975Y916150D01*
G01X75542Y915983D02*
X75292Y916233D01*
X75000Y916358D01*
X74667Y916400D01*
X74250Y916317D01*
X73958Y916108D01*
X73875Y915858D01*
X73917Y915608D01*
X74083Y915400D01*
X74917Y914983D01*
X75292Y914692D01*
X75542Y914275D01*
X75625Y913900D01*
X73875D01*
G01X37383Y860500D02*
Y858000D01*
X35717D01*
G01X33450D02*
Y860500D01*
X33950Y860000D01*
G01Y858000D02*
X32950D01*
G01X42963Y862925D02*
X29563D01*
G01X42963Y870125D02*
Y862925D01*
G01X29563Y870125D02*
X42963D01*
G01X29563Y862925D02*
Y870125D01*
G01X87017Y868000D02*
Y866208D01*
X86850Y865833D01*
X86517Y865583D01*
X86100Y865500D01*
X85683Y865583D01*
X85350Y865833D01*
X85183Y866208D01*
Y868000D01*
G01X83917Y866000D02*
X83667Y865708D01*
X83333Y865542D01*
X82958Y865500D01*
X82625Y865542D01*
X82292Y865750D01*
X82083Y866000D01*
X82042Y866250D01*
X82125Y866542D01*
X82417Y866750D01*
X82708Y866833D01*
X83083D01*
G01X82708D02*
X82458Y866958D01*
X82250Y867167D01*
X82167Y867417D01*
X82250Y867667D01*
X82458Y867875D01*
X82833Y868000D01*
X83208Y867958D01*
X83583Y867792D01*
G01X79900Y865500D02*
Y868000D01*
X80400Y867500D01*
G01Y865500D02*
X79400D01*
G01X71150Y894500D02*
Y899500D01*
X76150D01*
G01Y871500D02*
X71150D01*
Y876500D01*
G01X98850D02*
Y871500D01*
X93850D01*
G01X72157Y891406D02*
X69157D01*
G01X72157Y881563D02*
X70157D01*
G01X97843Y877626D02*
X100843D01*
G01X97843Y887469D02*
X99843D01*
G01X165219Y426131D02*
X165344Y425881D01*
X165427Y425589D01*
Y425256D01*
X165302Y424881D01*
X165094Y424589D01*
X164844Y424381D01*
X164427Y424214D01*
X164052Y424172D01*
X163677Y424256D01*
X163427Y424381D01*
X163177Y424631D01*
X163010Y424922D01*
X162927Y425214D01*
Y425506D01*
X163010Y425797D01*
X163135Y426047D01*
X163302Y426256D01*
G01X163969Y427522D02*
X164260Y427814D01*
X164427Y428064D01*
X164510Y428397D01*
X164427Y428689D01*
X164260Y428897D01*
X164010Y429064D01*
X163719Y429106D01*
X163469Y429064D01*
X163219Y428897D01*
X163010Y428647D01*
X162927Y428356D01*
X163010Y428022D01*
X163260Y427731D01*
X163635Y427564D01*
X164052Y427522D01*
X164594Y427606D01*
X164885Y427731D01*
X165177Y427939D01*
X165385Y428231D01*
X165427Y428522D01*
X165344Y428814D01*
X165135Y429022D01*
G01X163427Y430497D02*
X163135Y430747D01*
X162969Y431081D01*
X162927Y431456D01*
X162969Y431789D01*
X163177Y432122D01*
X163427Y432331D01*
X163677Y432372D01*
X163969Y432289D01*
X164177Y431997D01*
X164260Y431706D01*
Y431331D01*
G01Y431706D02*
X164385Y431956D01*
X164594Y432164D01*
X164844Y432247D01*
X165094Y432164D01*
X165302Y431956D01*
X165427Y431581D01*
X165385Y431206D01*
X165219Y430831D01*
G01X162927Y434514D02*
X162969Y434806D01*
X163094Y435139D01*
X163302Y435347D01*
X163594Y435431D01*
X163885Y435347D01*
X164135Y435097D01*
X164260Y434722D01*
Y434306D01*
X164344Y434056D01*
X164552Y433847D01*
X164844Y433764D01*
X165135Y433889D01*
X165344Y434181D01*
X165427Y434514D01*
X165344Y434847D01*
X165135Y435139D01*
X164844Y435264D01*
X164552Y435181D01*
X164344Y434972D01*
X164260Y434722D01*
Y434306D01*
X164135Y433931D01*
X163885Y433681D01*
X163594Y433597D01*
X163302Y433681D01*
X163094Y433889D01*
X162969Y434222D01*
X162927Y434514D01*
G01X178827Y474231D02*
X181327D01*
Y475272D01*
X181202Y475606D01*
X181035Y475814D01*
X180702Y475897D01*
X180369Y475814D01*
X180160Y475564D01*
X180035Y475272D01*
Y474231D01*
G01Y475272D02*
X178827Y475897D01*
G01Y478164D02*
X181327D01*
X180827Y477664D01*
G01X178827D02*
Y478664D01*
G01Y481264D02*
X181327D01*
X180827Y480764D01*
G01X178827D02*
Y481764D01*
G01X179327Y483447D02*
X179035Y483697D01*
X178869Y484031D01*
X178827Y484406D01*
X178869Y484739D01*
X179077Y485072D01*
X179327Y485281D01*
X179577Y485322D01*
X179869Y485239D01*
X180077Y484947D01*
X180160Y484656D01*
Y484281D01*
G01Y484656D02*
X180285Y484906D01*
X180494Y485114D01*
X180744Y485197D01*
X180994Y485114D01*
X181202Y484906D01*
X181327Y484531D01*
X181285Y484156D01*
X181119Y483781D01*
G01X181327Y487464D02*
X181244Y487131D01*
X181035Y486881D01*
X180785Y486714D01*
X180452Y486589D01*
X180077Y486547D01*
X179702Y486589D01*
X179369Y486714D01*
X179119Y486881D01*
X178910Y487131D01*
X178827Y487464D01*
X178910Y487797D01*
X179119Y488047D01*
X179369Y488214D01*
X179702Y488339D01*
X180077Y488381D01*
X180452Y488339D01*
X180785Y488214D01*
X181035Y488047D01*
X181244Y487797D01*
X181327Y487464D01*
G01X188768Y462280D02*
X184768D01*
Y469680D01*
G01X190427Y464564D02*
Y468564D01*
X197827D01*
G01X161560Y464556D02*
X161810Y464681D01*
X162102Y464764D01*
X162435D01*
X162810Y464639D01*
X163102Y464431D01*
X163310Y464181D01*
X163477Y463764D01*
X163519Y463389D01*
X163435Y463014D01*
X163310Y462764D01*
X163060Y462514D01*
X162769Y462347D01*
X162477Y462264D01*
X162185D01*
X161894Y462347D01*
X161644Y462472D01*
X161435Y462639D01*
G01X160169Y463306D02*
X159877Y463597D01*
X159627Y463764D01*
X159294Y463847D01*
X159002Y463764D01*
X158794Y463597D01*
X158627Y463347D01*
X158585Y463056D01*
X158627Y462806D01*
X158794Y462556D01*
X159044Y462347D01*
X159335Y462264D01*
X159669Y462347D01*
X159960Y462597D01*
X160127Y462972D01*
X160169Y463389D01*
X160085Y463931D01*
X159960Y464222D01*
X159752Y464514D01*
X159460Y464722D01*
X159169Y464764D01*
X158877Y464681D01*
X158669Y464472D01*
G01X155777Y462264D02*
Y464764D01*
X157319Y462972D01*
X155235D01*
G01X154094Y462639D02*
X153844Y462431D01*
X153552Y462306D01*
X153177Y462264D01*
X152802Y462347D01*
X152510Y462514D01*
X152302Y462806D01*
X152260Y463139D01*
X152344Y463472D01*
X152552Y463681D01*
X152844Y463847D01*
X153135Y463889D01*
X153427Y463847D01*
X153802Y463681D01*
X153677Y464764D01*
X152552D01*
G01X130927Y448331D02*
X133427D01*
Y449372D01*
X133302Y449706D01*
X133135Y449914D01*
X132802Y449997D01*
X132469Y449914D01*
X132260Y449664D01*
X132135Y449372D01*
Y448331D01*
G01Y449372D02*
X130927Y449997D01*
G01Y452264D02*
X133427D01*
X132927Y451764D01*
G01X130927D02*
Y452764D01*
G01Y455364D02*
X133427D01*
X132927Y454864D01*
G01X130927D02*
Y455864D01*
G01Y458464D02*
X133427D01*
X132927Y457964D01*
G01X130927D02*
Y458964D01*
G01Y461564D02*
X130969Y461856D01*
X131094Y462189D01*
X131302Y462397D01*
X131594Y462481D01*
X131885Y462397D01*
X132135Y462147D01*
X132260Y461772D01*
Y461356D01*
X132344Y461106D01*
X132552Y460897D01*
X132844Y460814D01*
X133135Y460939D01*
X133344Y461231D01*
X133427Y461564D01*
X133344Y461897D01*
X133135Y462189D01*
X132844Y462314D01*
X132552Y462231D01*
X132344Y462022D01*
X132260Y461772D01*
Y461356D01*
X132135Y460981D01*
X131885Y460731D01*
X131594Y460647D01*
X131302Y460731D01*
X131094Y460939D01*
X130969Y461272D01*
X130927Y461564D01*
G01X161119Y426031D02*
X161244Y425781D01*
X161327Y425489D01*
Y425156D01*
X161202Y424781D01*
X160994Y424489D01*
X160744Y424281D01*
X160327Y424114D01*
X159952Y424072D01*
X159577Y424156D01*
X159327Y424281D01*
X159077Y424531D01*
X158910Y424822D01*
X158827Y425114D01*
Y425406D01*
X158910Y425697D01*
X159035Y425947D01*
X159202Y426156D01*
G01X159869Y427422D02*
X160160Y427714D01*
X160327Y427964D01*
X160410Y428297D01*
X160327Y428589D01*
X160160Y428797D01*
X159910Y428964D01*
X159619Y429006D01*
X159369Y428964D01*
X159119Y428797D01*
X158910Y428547D01*
X158827Y428256D01*
X158910Y427922D01*
X159160Y427631D01*
X159535Y427464D01*
X159952Y427422D01*
X160494Y427506D01*
X160785Y427631D01*
X161077Y427839D01*
X161285Y428131D01*
X161327Y428422D01*
X161244Y428714D01*
X161035Y428922D01*
G01X159327Y430397D02*
X159035Y430647D01*
X158869Y430981D01*
X158827Y431356D01*
X158869Y431689D01*
X159077Y432022D01*
X159327Y432231D01*
X159577Y432272D01*
X159869Y432189D01*
X160077Y431897D01*
X160160Y431606D01*
Y431231D01*
G01Y431606D02*
X160285Y431856D01*
X160494Y432064D01*
X160744Y432147D01*
X160994Y432064D01*
X161202Y431856D01*
X161327Y431481D01*
X161285Y431106D01*
X161119Y430731D01*
G01X159202Y433497D02*
X158994Y433747D01*
X158869Y434039D01*
X158827Y434414D01*
X158910Y434789D01*
X159077Y435081D01*
X159369Y435289D01*
X159702Y435331D01*
X160035Y435247D01*
X160244Y435039D01*
X160410Y434747D01*
X160452Y434456D01*
X160410Y434164D01*
X160244Y433789D01*
X161327Y433914D01*
Y435039D01*
G01X148719Y422631D02*
X148844Y422381D01*
X148927Y422089D01*
Y421756D01*
X148802Y421381D01*
X148594Y421089D01*
X148344Y420881D01*
X147927Y420714D01*
X147552Y420672D01*
X147177Y420756D01*
X146927Y420881D01*
X146677Y421131D01*
X146510Y421422D01*
X146427Y421714D01*
Y422006D01*
X146510Y422297D01*
X146635Y422547D01*
X146802Y422756D01*
G01X147469Y424022D02*
X147760Y424314D01*
X147927Y424564D01*
X148010Y424897D01*
X147927Y425189D01*
X147760Y425397D01*
X147510Y425564D01*
X147219Y425606D01*
X146969Y425564D01*
X146719Y425397D01*
X146510Y425147D01*
X146427Y424856D01*
X146510Y424522D01*
X146760Y424231D01*
X147135Y424064D01*
X147552Y424022D01*
X148094Y424106D01*
X148385Y424231D01*
X148677Y424439D01*
X148885Y424731D01*
X148927Y425022D01*
X148844Y425314D01*
X148635Y425522D01*
G01X146927Y426997D02*
X146635Y427247D01*
X146469Y427581D01*
X146427Y427956D01*
X146469Y428289D01*
X146677Y428622D01*
X146927Y428831D01*
X147177Y428872D01*
X147469Y428789D01*
X147677Y428497D01*
X147760Y428206D01*
Y427831D01*
G01Y428206D02*
X147885Y428456D01*
X148094Y428664D01*
X148344Y428747D01*
X148594Y428664D01*
X148802Y428456D01*
X148927Y428081D01*
X148885Y427706D01*
X148719Y427331D01*
G01X147469Y430222D02*
X147760Y430514D01*
X147927Y430764D01*
X148010Y431097D01*
X147927Y431389D01*
X147760Y431597D01*
X147510Y431764D01*
X147219Y431806D01*
X146969Y431764D01*
X146719Y431597D01*
X146510Y431347D01*
X146427Y431056D01*
X146510Y430722D01*
X146760Y430431D01*
X147135Y430264D01*
X147552Y430222D01*
X148094Y430306D01*
X148385Y430431D01*
X148677Y430639D01*
X148885Y430931D01*
X148927Y431222D01*
X148844Y431514D01*
X148635Y431722D01*
G01X138404Y453597D02*
X138529Y453347D01*
X138612Y453055D01*
Y452722D01*
X138487Y452347D01*
X138279Y452055D01*
X138029Y451847D01*
X137612Y451680D01*
X137237Y451638D01*
X136862Y451722D01*
X136612Y451847D01*
X136362Y452097D01*
X136195Y452388D01*
X136112Y452680D01*
Y452972D01*
X136195Y453263D01*
X136320Y453513D01*
X136487Y453722D01*
G01X137154Y454988D02*
X137445Y455280D01*
X137612Y455530D01*
X137695Y455863D01*
X137612Y456155D01*
X137445Y456363D01*
X137195Y456530D01*
X136904Y456572D01*
X136654Y456530D01*
X136404Y456363D01*
X136195Y456113D01*
X136112Y455822D01*
X136195Y455488D01*
X136445Y455197D01*
X136820Y455030D01*
X137237Y454988D01*
X137779Y455072D01*
X138070Y455197D01*
X138362Y455405D01*
X138570Y455697D01*
X138612Y455988D01*
X138529Y456280D01*
X138320Y456488D01*
G01X136612Y457963D02*
X136320Y458213D01*
X136154Y458547D01*
X136112Y458922D01*
X136154Y459255D01*
X136362Y459588D01*
X136612Y459797D01*
X136862Y459838D01*
X137154Y459755D01*
X137362Y459463D01*
X137445Y459172D01*
Y458797D01*
G01Y459172D02*
X137570Y459422D01*
X137779Y459630D01*
X138029Y459713D01*
X138279Y459630D01*
X138487Y459422D01*
X138612Y459047D01*
X138570Y458672D01*
X138404Y458297D01*
G01X136112Y461897D02*
X136654Y461980D01*
X137112Y462105D01*
X137529Y462272D01*
X137987Y462480D01*
X138612Y462813D01*
Y461147D01*
G01X161560Y469056D02*
X161810Y469181D01*
X162102Y469264D01*
X162435D01*
X162810Y469139D01*
X163102Y468931D01*
X163310Y468681D01*
X163477Y468264D01*
X163519Y467889D01*
X163435Y467514D01*
X163310Y467264D01*
X163060Y467014D01*
X162769Y466847D01*
X162477Y466764D01*
X162185D01*
X161894Y466847D01*
X161644Y466972D01*
X161435Y467139D01*
G01X160169Y467806D02*
X159877Y468097D01*
X159627Y468264D01*
X159294Y468347D01*
X159002Y468264D01*
X158794Y468097D01*
X158627Y467847D01*
X158585Y467556D01*
X158627Y467306D01*
X158794Y467056D01*
X159044Y466847D01*
X159335Y466764D01*
X159669Y466847D01*
X159960Y467097D01*
X160127Y467472D01*
X160169Y467889D01*
X160085Y468431D01*
X159960Y468722D01*
X159752Y469014D01*
X159460Y469222D01*
X159169Y469264D01*
X158877Y469181D01*
X158669Y468972D01*
G01X155777Y466764D02*
Y469264D01*
X157319Y467472D01*
X155235D01*
G01X153969Y468847D02*
X153719Y469097D01*
X153427Y469222D01*
X153094Y469264D01*
X152677Y469181D01*
X152385Y468972D01*
X152302Y468722D01*
X152344Y468472D01*
X152510Y468264D01*
X153344Y467847D01*
X153719Y467556D01*
X153969Y467139D01*
X154052Y466764D01*
X152302D01*
G01X175127Y475014D02*
X174294D01*
Y474264D01*
X174544Y474014D01*
X174835Y473847D01*
X175252Y473764D01*
X175669Y473847D01*
X175960Y474014D01*
X176210Y474264D01*
X176377Y474556D01*
X176460Y474889D01*
Y475181D01*
X176377Y475431D01*
X176210Y475722D01*
X175960Y475972D01*
X175710Y476139D01*
X175377Y476264D01*
X175085D01*
X174752Y476181D01*
X174502Y476014D01*
G01X171777Y473764D02*
Y476264D01*
X173319Y474472D01*
X171235D01*
G01X131310Y424364D02*
Y421864D01*
X129644D01*
G01X128294Y422364D02*
X128044Y422072D01*
X127710Y421906D01*
X127335Y421864D01*
X127002Y421906D01*
X126669Y422114D01*
X126460Y422364D01*
X126419Y422614D01*
X126502Y422906D01*
X126794Y423114D01*
X127085Y423197D01*
X127460D01*
G01X127085D02*
X126835Y423322D01*
X126627Y423531D01*
X126544Y423781D01*
X126627Y424031D01*
X126835Y424239D01*
X127210Y424364D01*
X127585Y424322D01*
X127960Y424156D01*
G01X143790Y425489D02*
X130390D01*
G01X143790Y432689D02*
Y425489D01*
G01X130390Y432689D02*
X143790D01*
G01X130390Y425489D02*
Y432689D01*
G01X187844Y431264D02*
Y429472D01*
X187677Y429097D01*
X187344Y428847D01*
X186927Y428764D01*
X186510Y428847D01*
X186177Y429097D01*
X186010Y429472D01*
Y431264D01*
G01X184744Y429264D02*
X184494Y428972D01*
X184160Y428806D01*
X183785Y428764D01*
X183452Y428806D01*
X183119Y429014D01*
X182910Y429264D01*
X182869Y429514D01*
X182952Y429806D01*
X183244Y430014D01*
X183535Y430097D01*
X183910D01*
G01X183535D02*
X183285Y430222D01*
X183077Y430431D01*
X182994Y430681D01*
X183077Y430931D01*
X183285Y431139D01*
X183660Y431264D01*
X184035Y431222D01*
X184410Y431056D01*
G01X181519Y430847D02*
X181269Y431097D01*
X180977Y431222D01*
X180644Y431264D01*
X180227Y431181D01*
X179935Y430972D01*
X179852Y430722D01*
X179894Y430472D01*
X180060Y430264D01*
X180894Y429847D01*
X181269Y429556D01*
X181519Y429139D01*
X181602Y428764D01*
X179852D01*
G01X168977Y456764D02*
Y461764D01*
X173977D01*
G01Y433764D02*
X168977D01*
Y438764D01*
G01X196677D02*
Y433764D01*
X191677D01*
G01X169984Y453670D02*
X166984D01*
G01X169984Y443827D02*
X167984D01*
G01X196060Y483756D02*
X196310Y483881D01*
X196602Y483964D01*
X196935D01*
X197310Y483839D01*
X197602Y483631D01*
X197810Y483381D01*
X197977Y482964D01*
X198019Y482589D01*
X197935Y482214D01*
X197810Y481964D01*
X197560Y481714D01*
X197269Y481547D01*
X196977Y481464D01*
X196685D01*
X196394Y481547D01*
X196144Y481672D01*
X195935Y481839D01*
G01X194669Y482506D02*
X194377Y482797D01*
X194127Y482964D01*
X193794Y483047D01*
X193502Y482964D01*
X193294Y482797D01*
X193127Y482547D01*
X193085Y482256D01*
X193127Y482006D01*
X193294Y481756D01*
X193544Y481547D01*
X193835Y481464D01*
X194169Y481547D01*
X194460Y481797D01*
X194627Y482172D01*
X194669Y482589D01*
X194585Y483131D01*
X194460Y483422D01*
X194252Y483714D01*
X193960Y483922D01*
X193669Y483964D01*
X193377Y483881D01*
X193169Y483672D01*
G01X190277Y481464D02*
Y483964D01*
X191819Y482172D01*
X189735D01*
G01X187677Y481464D02*
X187385Y481506D01*
X187052Y481631D01*
X186844Y481839D01*
X186760Y482131D01*
X186844Y482422D01*
X187094Y482672D01*
X187469Y482797D01*
X187885D01*
X188135Y482881D01*
X188344Y483089D01*
X188427Y483381D01*
X188302Y483672D01*
X188010Y483881D01*
X187677Y483964D01*
X187344Y483881D01*
X187052Y483672D01*
X186927Y483381D01*
X187010Y483089D01*
X187219Y482881D01*
X187469Y482797D01*
X187885D01*
X188260Y482672D01*
X188510Y482422D01*
X188594Y482131D01*
X188510Y481839D01*
X188302Y481631D01*
X187969Y481506D01*
X187677Y481464D01*
G01X197760Y477564D02*
Y480064D01*
X196719D01*
X196385Y479939D01*
X196177Y479772D01*
X196094Y479439D01*
X196177Y479106D01*
X196427Y478897D01*
X196719Y478772D01*
X197760D01*
G01X196719D02*
X196094Y477564D01*
G01X193827D02*
Y480064D01*
X194327Y479564D01*
G01Y477564D02*
X193327D01*
G01X190727D02*
Y480064D01*
X191227Y479564D01*
G01Y477564D02*
X190227D01*
G01X188419Y479647D02*
X188169Y479897D01*
X187877Y480022D01*
X187544Y480064D01*
X187127Y479981D01*
X186835Y479772D01*
X186752Y479522D01*
X186794Y479272D01*
X186960Y479064D01*
X187794Y478647D01*
X188169Y478356D01*
X188419Y477939D01*
X188502Y477564D01*
X186752D01*
G01X184610D02*
X184527Y478106D01*
X184402Y478564D01*
X184235Y478981D01*
X184027Y479439D01*
X183694Y480064D01*
X185360D01*
G01X100500Y895100D02*
Y853700D01*
X151100D01*
Y895100D01*
X100500D01*
G01X166650Y845000D02*
Y842500D01*
G01X167608Y845000D02*
X165692D01*
G01X162633Y844792D02*
X162883Y844917D01*
X163175Y845000D01*
X163508D01*
X163883Y844875D01*
X164175Y844667D01*
X164383Y844417D01*
X164550Y844000D01*
X164592Y843625D01*
X164508Y843250D01*
X164383Y843000D01*
X164133Y842750D01*
X163842Y842583D01*
X163550Y842500D01*
X163258D01*
X162967Y842583D01*
X162717Y842708D01*
X162508Y842875D01*
G01X160450Y842500D02*
Y845000D01*
X160950Y844500D01*
G01Y842500D02*
X159950D01*
G01X156850D02*
Y845000D01*
X158392Y843208D01*
X156308D01*
G01X170800Y846785D02*
Y857985D01*
G01X152800Y846785D02*
X170800D01*
G01X152800Y857985D02*
Y846785D01*
G01X138733Y918292D02*
X138983Y918417D01*
X139275Y918500D01*
X139608D01*
X139983Y918375D01*
X140275Y918167D01*
X140483Y917917D01*
X140650Y917500D01*
X140692Y917125D01*
X140608Y916750D01*
X140483Y916500D01*
X140233Y916250D01*
X139942Y916083D01*
X139650Y916000D01*
X139358D01*
X139067Y916083D01*
X138817Y916208D01*
X138608Y916375D01*
G01X137342Y917042D02*
X137050Y917333D01*
X136800Y917500D01*
X136467Y917583D01*
X136175Y917500D01*
X135967Y917333D01*
X135800Y917083D01*
X135758Y916792D01*
X135800Y916542D01*
X135967Y916292D01*
X136217Y916083D01*
X136508Y916000D01*
X136842Y916083D01*
X137133Y916333D01*
X137300Y916708D01*
X137342Y917125D01*
X137258Y917667D01*
X137133Y917958D01*
X136925Y918250D01*
X136633Y918458D01*
X136342Y918500D01*
X136050Y918417D01*
X135842Y918208D01*
G01X134242Y918083D02*
X133992Y918333D01*
X133700Y918458D01*
X133367Y918500D01*
X132950Y918417D01*
X132658Y918208D01*
X132575Y917958D01*
X132617Y917708D01*
X132783Y917500D01*
X133617Y917083D01*
X133992Y916792D01*
X134242Y916375D01*
X134325Y916000D01*
X132575D01*
G01X131058Y916292D02*
X130767Y916083D01*
X130433Y916000D01*
X130100Y916083D01*
X129808Y916333D01*
X129600Y916708D01*
X129517Y917083D01*
Y917542D01*
X129600Y917917D01*
X129808Y918250D01*
X130058Y918417D01*
X130350Y918500D01*
X130683Y918417D01*
X130933Y918250D01*
X131100Y918000D01*
X131183Y917667D01*
X131100Y917375D01*
X130892Y917083D01*
X130642Y916917D01*
X130350Y916875D01*
X130017Y916958D01*
X129767Y917167D01*
X129517Y917542D01*
G01X131000Y898967D02*
X133500D01*
Y900008D01*
X133375Y900342D01*
X133208Y900550D01*
X132875Y900633D01*
X132542Y900550D01*
X132333Y900300D01*
X132208Y900008D01*
Y898967D01*
G01Y900008D02*
X131000Y900633D01*
G01Y902900D02*
X133500D01*
X133000Y902400D01*
G01X131000D02*
Y903400D01*
G01Y906000D02*
X133500D01*
X133000Y905500D01*
G01X131000D02*
Y906500D01*
G01X133500Y909100D02*
X133417Y908767D01*
X133208Y908517D01*
X132958Y908350D01*
X132625Y908225D01*
X132250Y908183D01*
X131875Y908225D01*
X131542Y908350D01*
X131292Y908517D01*
X131083Y908767D01*
X131000Y909100D01*
X131083Y909433D01*
X131292Y909683D01*
X131542Y909850D01*
X131875Y909975D01*
X132250Y910017D01*
X132625Y909975D01*
X132958Y909850D01*
X133208Y909683D01*
X133417Y909433D01*
X133500Y909100D01*
G01X131500Y911283D02*
X131208Y911533D01*
X131042Y911867D01*
X131000Y912242D01*
X131042Y912575D01*
X131250Y912908D01*
X131500Y913117D01*
X131750Y913158D01*
X132042Y913075D01*
X132250Y912783D01*
X132333Y912492D01*
Y912117D01*
G01Y912492D02*
X132458Y912742D01*
X132667Y912950D01*
X132917Y913033D01*
X133167Y912950D01*
X133375Y912742D01*
X133500Y912367D01*
X133458Y911992D01*
X133292Y911617D01*
G01X123736Y898274D02*
X119736D01*
Y905674D01*
G01X138292Y900267D02*
X138417Y900017D01*
X138500Y899725D01*
Y899392D01*
X138375Y899017D01*
X138167Y898725D01*
X137917Y898517D01*
X137500Y898350D01*
X137125Y898308D01*
X136750Y898392D01*
X136500Y898517D01*
X136250Y898767D01*
X136083Y899058D01*
X136000Y899350D01*
Y899642D01*
X136083Y899933D01*
X136208Y900183D01*
X136375Y900392D01*
G01X137042Y901658D02*
X137333Y901950D01*
X137500Y902200D01*
X137583Y902533D01*
X137500Y902825D01*
X137333Y903033D01*
X137083Y903200D01*
X136792Y903242D01*
X136542Y903200D01*
X136292Y903033D01*
X136083Y902783D01*
X136000Y902492D01*
X136083Y902158D01*
X136333Y901867D01*
X136708Y901700D01*
X137125Y901658D01*
X137667Y901742D01*
X137958Y901867D01*
X138250Y902075D01*
X138458Y902367D01*
X138500Y902658D01*
X138417Y902950D01*
X138208Y903158D01*
G01X138083Y904758D02*
X138333Y905008D01*
X138458Y905300D01*
X138500Y905633D01*
X138417Y906050D01*
X138208Y906342D01*
X137958Y906425D01*
X137708Y906383D01*
X137500Y906217D01*
X137083Y905383D01*
X136792Y905008D01*
X136375Y904758D01*
X136000Y904675D01*
Y906425D01*
G01Y908567D02*
X136542Y908650D01*
X137000Y908775D01*
X137417Y908942D01*
X137875Y909150D01*
X138500Y909483D01*
Y907817D01*
G01X119033Y914500D02*
Y917000D01*
X117992D01*
X117658Y916875D01*
X117450Y916708D01*
X117367Y916375D01*
X117450Y916042D01*
X117700Y915833D01*
X117992Y915708D01*
X119033D01*
G01X117992D02*
X117367Y914500D01*
G01X115100D02*
Y917000D01*
X115600Y916500D01*
G01Y914500D02*
X114600D01*
G01X112000D02*
Y917000D01*
X112500Y916500D01*
G01Y914500D02*
X111500D01*
G01X108900Y917000D02*
X109233Y916917D01*
X109483Y916708D01*
X109650Y916458D01*
X109775Y916125D01*
X109817Y915750D01*
X109775Y915375D01*
X109650Y915042D01*
X109483Y914792D01*
X109233Y914583D01*
X108900Y914500D01*
X108567Y914583D01*
X108317Y914792D01*
X108150Y915042D01*
X108025Y915375D01*
X107983Y915750D01*
X108025Y916125D01*
X108150Y916458D01*
X108317Y916708D01*
X108567Y916917D01*
X108900Y917000D01*
G01X106592Y915542D02*
X106300Y915833D01*
X106050Y916000D01*
X105717Y916083D01*
X105425Y916000D01*
X105217Y915833D01*
X105050Y915583D01*
X105008Y915292D01*
X105050Y915042D01*
X105217Y914792D01*
X105467Y914583D01*
X105758Y914500D01*
X106092Y914583D01*
X106383Y914833D01*
X106550Y915208D01*
X106592Y915625D01*
X106508Y916167D01*
X106383Y916458D01*
X106175Y916750D01*
X105883Y916958D01*
X105592Y917000D01*
X105300Y916917D01*
X105092Y916708D01*
G01X179792Y912267D02*
X179917Y912017D01*
X180000Y911725D01*
Y911392D01*
X179875Y911017D01*
X179667Y910725D01*
X179417Y910517D01*
X179000Y910350D01*
X178625Y910308D01*
X178250Y910392D01*
X178000Y910517D01*
X177750Y910767D01*
X177583Y911058D01*
X177500Y911350D01*
Y911642D01*
X177583Y911933D01*
X177708Y912183D01*
X177875Y912392D01*
G01X178542Y913658D02*
X178833Y913950D01*
X179000Y914200D01*
X179083Y914533D01*
X179000Y914825D01*
X178833Y915033D01*
X178583Y915200D01*
X178292Y915242D01*
X178042Y915200D01*
X177792Y915033D01*
X177583Y914783D01*
X177500Y914492D01*
X177583Y914158D01*
X177833Y913867D01*
X178208Y913700D01*
X178625Y913658D01*
X179167Y913742D01*
X179458Y913867D01*
X179750Y914075D01*
X179958Y914367D01*
X180000Y914658D01*
X179917Y914950D01*
X179708Y915158D01*
G01X178000Y916633D02*
X177708Y916883D01*
X177542Y917217D01*
X177500Y917592D01*
X177542Y917925D01*
X177750Y918258D01*
X178000Y918467D01*
X178250Y918508D01*
X178542Y918425D01*
X178750Y918133D01*
X178833Y917842D01*
Y917467D01*
G01Y917842D02*
X178958Y918092D01*
X179167Y918300D01*
X179417Y918383D01*
X179667Y918300D01*
X179875Y918092D01*
X180000Y917717D01*
X179958Y917342D01*
X179792Y916967D01*
G01X179583Y919858D02*
X179833Y920108D01*
X179958Y920400D01*
X180000Y920733D01*
X179917Y921150D01*
X179708Y921442D01*
X179458Y921525D01*
X179208Y921483D01*
X179000Y921317D01*
X178583Y920483D01*
X178292Y920108D01*
X177875Y919858D01*
X177500Y919775D01*
Y921525D01*
G01X192792Y912267D02*
X192917Y912017D01*
X193000Y911725D01*
Y911392D01*
X192875Y911017D01*
X192667Y910725D01*
X192417Y910517D01*
X192000Y910350D01*
X191625Y910308D01*
X191250Y910392D01*
X191000Y910517D01*
X190750Y910767D01*
X190583Y911058D01*
X190500Y911350D01*
Y911642D01*
X190583Y911933D01*
X190708Y912183D01*
X190875Y912392D01*
G01X191542Y913658D02*
X191833Y913950D01*
X192000Y914200D01*
X192083Y914533D01*
X192000Y914825D01*
X191833Y915033D01*
X191583Y915200D01*
X191292Y915242D01*
X191042Y915200D01*
X190792Y915033D01*
X190583Y914783D01*
X190500Y914492D01*
X190583Y914158D01*
X190833Y913867D01*
X191208Y913700D01*
X191625Y913658D01*
X192167Y913742D01*
X192458Y913867D01*
X192750Y914075D01*
X192958Y914367D01*
X193000Y914658D01*
X192917Y914950D01*
X192708Y915158D01*
G01X191000Y916633D02*
X190708Y916883D01*
X190542Y917217D01*
X190500Y917592D01*
X190542Y917925D01*
X190750Y918258D01*
X191000Y918467D01*
X191250Y918508D01*
X191542Y918425D01*
X191750Y918133D01*
X191833Y917842D01*
Y917467D01*
G01Y917842D02*
X191958Y918092D01*
X192167Y918300D01*
X192417Y918383D01*
X192667Y918300D01*
X192875Y918092D01*
X193000Y917717D01*
X192958Y917342D01*
X192792Y916967D01*
G01X191000Y919733D02*
X190708Y919983D01*
X190542Y920317D01*
X190500Y920692D01*
X190542Y921025D01*
X190750Y921358D01*
X191000Y921567D01*
X191250Y921608D01*
X191542Y921525D01*
X191750Y921233D01*
X191833Y920942D01*
Y920567D01*
G01Y920942D02*
X191958Y921192D01*
X192167Y921400D01*
X192417Y921483D01*
X192667Y921400D01*
X192875Y921192D01*
X193000Y920817D01*
X192958Y920442D01*
X192792Y920067D01*
G01X184792Y912267D02*
X184917Y912017D01*
X185000Y911725D01*
Y911392D01*
X184875Y911017D01*
X184667Y910725D01*
X184417Y910517D01*
X184000Y910350D01*
X183625Y910308D01*
X183250Y910392D01*
X183000Y910517D01*
X182750Y910767D01*
X182583Y911058D01*
X182500Y911350D01*
Y911642D01*
X182583Y911933D01*
X182708Y912183D01*
X182875Y912392D01*
G01X183542Y913658D02*
X183833Y913950D01*
X184000Y914200D01*
X184083Y914533D01*
X184000Y914825D01*
X183833Y915033D01*
X183583Y915200D01*
X183292Y915242D01*
X183042Y915200D01*
X182792Y915033D01*
X182583Y914783D01*
X182500Y914492D01*
X182583Y914158D01*
X182833Y913867D01*
X183208Y913700D01*
X183625Y913658D01*
X184167Y913742D01*
X184458Y913867D01*
X184750Y914075D01*
X184958Y914367D01*
X185000Y914658D01*
X184917Y914950D01*
X184708Y915158D01*
G01X183000Y916633D02*
X182708Y916883D01*
X182542Y917217D01*
X182500Y917592D01*
X182542Y917925D01*
X182750Y918258D01*
X183000Y918467D01*
X183250Y918508D01*
X183542Y918425D01*
X183750Y918133D01*
X183833Y917842D01*
Y917467D01*
G01Y917842D02*
X183958Y918092D01*
X184167Y918300D01*
X184417Y918383D01*
X184667Y918300D01*
X184875Y918092D01*
X185000Y917717D01*
X184958Y917342D01*
X184792Y916967D01*
G01X182500Y921150D02*
X185000D01*
X183208Y919608D01*
Y921692D01*
G01X114883Y899500D02*
Y897000D01*
X113217D01*
G01X111742Y899083D02*
X111492Y899333D01*
X111200Y899458D01*
X110867Y899500D01*
X110450Y899417D01*
X110158Y899208D01*
X110075Y898958D01*
X110117Y898708D01*
X110283Y898500D01*
X111117Y898083D01*
X111492Y897792D01*
X111742Y897375D01*
X111825Y897000D01*
X110075D01*
G01X170800Y885185D02*
Y873985D01*
G01X152800Y885185D02*
X170800D01*
G01X152800Y873985D02*
Y885185D01*
G01X168150Y930500D02*
Y928000D01*
G01X169108Y930500D02*
X167192D01*
G01X164133Y930292D02*
X164383Y930417D01*
X164675Y930500D01*
X165008D01*
X165383Y930375D01*
X165675Y930167D01*
X165883Y929917D01*
X166050Y929500D01*
X166092Y929125D01*
X166008Y928750D01*
X165883Y928500D01*
X165633Y928250D01*
X165342Y928083D01*
X165050Y928000D01*
X164758D01*
X164467Y928083D01*
X164217Y928208D01*
X164008Y928375D01*
G01X161950Y928000D02*
Y930500D01*
X162450Y930000D01*
G01Y928000D02*
X161450D01*
G01X159767Y928500D02*
X159517Y928208D01*
X159183Y928042D01*
X158808Y928000D01*
X158475Y928042D01*
X158142Y928250D01*
X157933Y928500D01*
X157892Y928750D01*
X157975Y929042D01*
X158267Y929250D01*
X158558Y929333D01*
X158933D01*
G01X158558D02*
X158308Y929458D01*
X158100Y929667D01*
X158017Y929917D01*
X158100Y930167D01*
X158308Y930375D01*
X158683Y930500D01*
X159058Y930458D01*
X159433Y930292D01*
G01X152800Y886085D02*
Y897285D01*
G01X170800Y886085D02*
X152800D01*
G01X170800Y897285D02*
Y886085D01*
G01X152800Y924485D02*
Y913285D01*
G01X170800Y924485D02*
X152800D01*
G01X170800Y913285D02*
Y924485D01*
G01X228327Y460731D02*
X230827D01*
Y461772D01*
X230702Y462106D01*
X230535Y462314D01*
X230202Y462397D01*
X229869Y462314D01*
X229660Y462064D01*
X229535Y461772D01*
Y460731D01*
G01Y461772D02*
X228327Y462397D01*
G01Y464664D02*
X230827D01*
X230327Y464164D01*
G01X228327D02*
Y465164D01*
G01Y467764D02*
X230827D01*
X230327Y467264D01*
G01X228327D02*
Y468264D01*
G01X230410Y470072D02*
X230660Y470322D01*
X230785Y470614D01*
X230827Y470947D01*
X230744Y471364D01*
X230535Y471656D01*
X230285Y471739D01*
X230035Y471697D01*
X229827Y471531D01*
X229410Y470697D01*
X229119Y470322D01*
X228702Y470072D01*
X228327Y469989D01*
Y471739D01*
G01X230410Y473172D02*
X230660Y473422D01*
X230785Y473714D01*
X230827Y474047D01*
X230744Y474464D01*
X230535Y474756D01*
X230285Y474839D01*
X230035Y474797D01*
X229827Y474631D01*
X229410Y473797D01*
X229119Y473422D01*
X228702Y473172D01*
X228327Y473089D01*
Y474839D01*
G01X221563Y460538D02*
X217563D01*
Y467938D01*
G01X235619Y463031D02*
X235744Y462781D01*
X235827Y462489D01*
Y462156D01*
X235702Y461781D01*
X235494Y461489D01*
X235244Y461281D01*
X234827Y461114D01*
X234452Y461072D01*
X234077Y461156D01*
X233827Y461281D01*
X233577Y461531D01*
X233410Y461822D01*
X233327Y462114D01*
Y462406D01*
X233410Y462697D01*
X233535Y462947D01*
X233702Y463156D01*
G01X234369Y464422D02*
X234660Y464714D01*
X234827Y464964D01*
X234910Y465297D01*
X234827Y465589D01*
X234660Y465797D01*
X234410Y465964D01*
X234119Y466006D01*
X233869Y465964D01*
X233619Y465797D01*
X233410Y465547D01*
X233327Y465256D01*
X233410Y464922D01*
X233660Y464631D01*
X234035Y464464D01*
X234452Y464422D01*
X234994Y464506D01*
X235285Y464631D01*
X235577Y464839D01*
X235785Y465131D01*
X235827Y465422D01*
X235744Y465714D01*
X235535Y465922D01*
G01X233327Y468814D02*
X235827D01*
X234035Y467272D01*
Y469356D01*
G01X234369Y470622D02*
X234660Y470914D01*
X234827Y471164D01*
X234910Y471497D01*
X234827Y471789D01*
X234660Y471997D01*
X234410Y472164D01*
X234119Y472206D01*
X233869Y472164D01*
X233619Y471997D01*
X233410Y471747D01*
X233327Y471456D01*
X233410Y471122D01*
X233660Y470831D01*
X234035Y470664D01*
X234452Y470622D01*
X234994Y470706D01*
X235285Y470831D01*
X235577Y471039D01*
X235785Y471331D01*
X235827Y471622D01*
X235744Y471914D01*
X235535Y472122D01*
G01X278219Y473631D02*
X278344Y473381D01*
X278427Y473089D01*
Y472756D01*
X278302Y472381D01*
X278094Y472089D01*
X277844Y471881D01*
X277427Y471714D01*
X277052Y471672D01*
X276677Y471756D01*
X276427Y471881D01*
X276177Y472131D01*
X276010Y472422D01*
X275927Y472714D01*
Y473006D01*
X276010Y473297D01*
X276135Y473547D01*
X276302Y473756D01*
G01X276969Y475022D02*
X277260Y475314D01*
X277427Y475564D01*
X277510Y475897D01*
X277427Y476189D01*
X277260Y476397D01*
X277010Y476564D01*
X276719Y476606D01*
X276469Y476564D01*
X276219Y476397D01*
X276010Y476147D01*
X275927Y475856D01*
X276010Y475522D01*
X276260Y475231D01*
X276635Y475064D01*
X277052Y475022D01*
X277594Y475106D01*
X277885Y475231D01*
X278177Y475439D01*
X278385Y475731D01*
X278427Y476022D01*
X278344Y476314D01*
X278135Y476522D01*
G01X276302Y477997D02*
X276094Y478247D01*
X275969Y478539D01*
X275927Y478914D01*
X276010Y479289D01*
X276177Y479581D01*
X276469Y479789D01*
X276802Y479831D01*
X277135Y479747D01*
X277344Y479539D01*
X277510Y479247D01*
X277552Y478956D01*
X277510Y478664D01*
X277344Y478289D01*
X278427Y478414D01*
Y479539D01*
G01Y482014D02*
X278344Y481681D01*
X278135Y481431D01*
X277885Y481264D01*
X277552Y481139D01*
X277177Y481097D01*
X276802Y481139D01*
X276469Y481264D01*
X276219Y481431D01*
X276010Y481681D01*
X275927Y482014D01*
X276010Y482347D01*
X276219Y482597D01*
X276469Y482764D01*
X276802Y482889D01*
X277177Y482931D01*
X277552Y482889D01*
X277885Y482764D01*
X278135Y482597D01*
X278344Y482347D01*
X278427Y482014D01*
G01X290619Y473031D02*
X290744Y472781D01*
X290827Y472489D01*
Y472156D01*
X290702Y471781D01*
X290494Y471489D01*
X290244Y471281D01*
X289827Y471114D01*
X289452Y471072D01*
X289077Y471156D01*
X288827Y471281D01*
X288577Y471531D01*
X288410Y471822D01*
X288327Y472114D01*
Y472406D01*
X288410Y472697D01*
X288535Y472947D01*
X288702Y473156D01*
G01X289369Y474422D02*
X289660Y474714D01*
X289827Y474964D01*
X289910Y475297D01*
X289827Y475589D01*
X289660Y475797D01*
X289410Y475964D01*
X289119Y476006D01*
X288869Y475964D01*
X288619Y475797D01*
X288410Y475547D01*
X288327Y475256D01*
X288410Y474922D01*
X288660Y474631D01*
X289035Y474464D01*
X289452Y474422D01*
X289994Y474506D01*
X290285Y474631D01*
X290577Y474839D01*
X290785Y475131D01*
X290827Y475422D01*
X290744Y475714D01*
X290535Y475922D01*
G01X288702Y477397D02*
X288494Y477647D01*
X288369Y477939D01*
X288327Y478314D01*
X288410Y478689D01*
X288577Y478981D01*
X288869Y479189D01*
X289202Y479231D01*
X289535Y479147D01*
X289744Y478939D01*
X289910Y478647D01*
X289952Y478356D01*
X289910Y478064D01*
X289744Y477689D01*
X290827Y477814D01*
Y478939D01*
G01X288327Y481414D02*
X290827D01*
X290327Y480914D01*
G01X288327D02*
Y481914D01*
G01X282719Y473631D02*
X282844Y473381D01*
X282927Y473089D01*
Y472756D01*
X282802Y472381D01*
X282594Y472089D01*
X282344Y471881D01*
X281927Y471714D01*
X281552Y471672D01*
X281177Y471756D01*
X280927Y471881D01*
X280677Y472131D01*
X280510Y472422D01*
X280427Y472714D01*
Y473006D01*
X280510Y473297D01*
X280635Y473547D01*
X280802Y473756D01*
G01X281469Y475022D02*
X281760Y475314D01*
X281927Y475564D01*
X282010Y475897D01*
X281927Y476189D01*
X281760Y476397D01*
X281510Y476564D01*
X281219Y476606D01*
X280969Y476564D01*
X280719Y476397D01*
X280510Y476147D01*
X280427Y475856D01*
X280510Y475522D01*
X280760Y475231D01*
X281135Y475064D01*
X281552Y475022D01*
X282094Y475106D01*
X282385Y475231D01*
X282677Y475439D01*
X282885Y475731D01*
X282927Y476022D01*
X282844Y476314D01*
X282635Y476522D01*
G01X280802Y477997D02*
X280594Y478247D01*
X280469Y478539D01*
X280427Y478914D01*
X280510Y479289D01*
X280677Y479581D01*
X280969Y479789D01*
X281302Y479831D01*
X281635Y479747D01*
X281844Y479539D01*
X282010Y479247D01*
X282052Y478956D01*
X282010Y478664D01*
X281844Y478289D01*
X282927Y478414D01*
Y479539D01*
G01X282510Y481222D02*
X282760Y481472D01*
X282885Y481764D01*
X282927Y482097D01*
X282844Y482514D01*
X282635Y482806D01*
X282385Y482889D01*
X282135Y482847D01*
X281927Y482681D01*
X281510Y481847D01*
X281219Y481472D01*
X280802Y481222D01*
X280427Y481139D01*
Y482889D01*
G01X215883Y461600D02*
Y459100D01*
X214217D01*
G01X211450D02*
Y461600D01*
X212992Y459808D01*
X210908D01*
G01X198327Y457364D02*
Y415964D01*
X248927D01*
Y457364D01*
X198327D01*
G01X195670Y439890D02*
X198670D01*
G01X195670Y449733D02*
X197670D01*
G01X264077Y407864D02*
Y405364D01*
G01X265035Y407864D02*
X263119D01*
G01X260060Y407656D02*
X260310Y407781D01*
X260602Y407864D01*
X260935D01*
X261310Y407739D01*
X261602Y407531D01*
X261810Y407281D01*
X261977Y406864D01*
X262019Y406489D01*
X261935Y406114D01*
X261810Y405864D01*
X261560Y405614D01*
X261269Y405447D01*
X260977Y405364D01*
X260685D01*
X260394Y405447D01*
X260144Y405572D01*
X259935Y405739D01*
G01X257877Y405364D02*
Y407864D01*
X258377Y407364D01*
G01Y405364D02*
X257377D01*
G01X255569Y407447D02*
X255319Y407697D01*
X255027Y407822D01*
X254694Y407864D01*
X254277Y407781D01*
X253985Y407572D01*
X253902Y407322D01*
X253944Y407072D01*
X254110Y406864D01*
X254944Y406447D01*
X255319Y406156D01*
X255569Y405739D01*
X255652Y405364D01*
X253902D01*
G01X268627Y447849D02*
Y436649D01*
G01X250627Y447849D02*
X268627D01*
G01X250627Y436649D02*
Y447849D01*
G01X268627Y409449D02*
Y420649D01*
G01X250627Y409449D02*
X268627D01*
G01X250627Y420649D02*
Y409449D01*
G01Y448749D02*
Y459949D01*
G01X268627Y448749D02*
X250627D01*
G01X268627Y459949D02*
Y448749D01*
G01X227160Y481156D02*
X227410Y481281D01*
X227702Y481364D01*
X228035D01*
X228410Y481239D01*
X228702Y481031D01*
X228910Y480781D01*
X229077Y480364D01*
X229119Y479989D01*
X229035Y479614D01*
X228910Y479364D01*
X228660Y479114D01*
X228369Y478947D01*
X228077Y478864D01*
X227785D01*
X227494Y478947D01*
X227244Y479072D01*
X227035Y479239D01*
G01X225769Y479906D02*
X225477Y480197D01*
X225227Y480364D01*
X224894Y480447D01*
X224602Y480364D01*
X224394Y480197D01*
X224227Y479947D01*
X224185Y479656D01*
X224227Y479406D01*
X224394Y479156D01*
X224644Y478947D01*
X224935Y478864D01*
X225269Y478947D01*
X225560Y479197D01*
X225727Y479572D01*
X225769Y479989D01*
X225685Y480531D01*
X225560Y480822D01*
X225352Y481114D01*
X225060Y481322D01*
X224769Y481364D01*
X224477Y481281D01*
X224269Y481072D01*
G01X221377Y478864D02*
Y481364D01*
X222919Y479572D01*
X220835D01*
G01X218860Y478864D02*
X218777Y479406D01*
X218652Y479864D01*
X218485Y480281D01*
X218277Y480739D01*
X217944Y481364D01*
X219610D01*
G01X214860Y477264D02*
Y479764D01*
X213819D01*
X213485Y479639D01*
X213277Y479472D01*
X213194Y479139D01*
X213277Y478806D01*
X213527Y478597D01*
X213819Y478472D01*
X214860D01*
G01X213819D02*
X213194Y477264D01*
G01X210927D02*
Y479764D01*
X211427Y479264D01*
G01Y477264D02*
X210427D01*
G01X207827D02*
Y479764D01*
X208327Y479264D01*
G01Y477264D02*
X207327D01*
G01X205519Y479347D02*
X205269Y479597D01*
X204977Y479722D01*
X204644Y479764D01*
X204227Y479681D01*
X203935Y479472D01*
X203852Y479222D01*
X203894Y478972D01*
X204060Y478764D01*
X204894Y478347D01*
X205269Y478056D01*
X205519Y477639D01*
X205602Y477264D01*
X203852D01*
G01X202544Y477639D02*
X202294Y477431D01*
X202002Y477306D01*
X201627Y477264D01*
X201252Y477347D01*
X200960Y477514D01*
X200752Y477806D01*
X200710Y478139D01*
X200794Y478472D01*
X201002Y478681D01*
X201294Y478847D01*
X201585Y478889D01*
X201877Y478847D01*
X202252Y478681D01*
X202127Y479764D01*
X201002D01*
G01X265077Y492864D02*
Y490364D01*
G01X266035Y492864D02*
X264119D01*
G01X261060Y492656D02*
X261310Y492781D01*
X261602Y492864D01*
X261935D01*
X262310Y492739D01*
X262602Y492531D01*
X262810Y492281D01*
X262977Y491864D01*
X263019Y491489D01*
X262935Y491114D01*
X262810Y490864D01*
X262560Y490614D01*
X262269Y490447D01*
X261977Y490364D01*
X261685D01*
X261394Y490447D01*
X261144Y490572D01*
X260935Y490739D01*
G01X258877Y490364D02*
Y492864D01*
X259377Y492364D01*
G01Y490364D02*
X258377D01*
G01X255777D02*
Y492864D01*
X256277Y492364D01*
G01Y490364D02*
X255277D01*
G01X250627Y487149D02*
Y475949D01*
G01X268627Y487149D02*
X250627D01*
G01X268627Y475949D02*
Y487149D01*
G01X197750Y911700D02*
Y912533D01*
X197000D01*
X196750Y912283D01*
X196583Y911992D01*
X196500Y911575D01*
X196583Y911158D01*
X196750Y910867D01*
X197000Y910617D01*
X197292Y910450D01*
X197625Y910367D01*
X197917D01*
X198167Y910450D01*
X198458Y910617D01*
X198708Y910867D01*
X198875Y911117D01*
X199000Y911450D01*
Y911742D01*
X198917Y912075D01*
X198750Y912325D01*
G01X196500Y914550D02*
X199000D01*
X198500Y914050D01*
G01X196500D02*
Y915050D01*
G01X299905Y463336D02*
Y464169D01*
X299155D01*
X298905Y463919D01*
X298738Y463628D01*
X298655Y463211D01*
X298738Y462794D01*
X298905Y462503D01*
X299155Y462253D01*
X299447Y462086D01*
X299780Y462003D01*
X300072D01*
X300322Y462086D01*
X300613Y462253D01*
X300863Y462503D01*
X301030Y462753D01*
X301155Y463086D01*
Y463378D01*
X301072Y463711D01*
X300905Y463961D01*
G01X299155Y465269D02*
X298863Y465519D01*
X298697Y465853D01*
X298655Y466228D01*
X298697Y466561D01*
X298905Y466894D01*
X299155Y467103D01*
X299405Y467144D01*
X299697Y467061D01*
X299905Y466769D01*
X299988Y466478D01*
Y466103D01*
G01Y466478D02*
X300113Y466728D01*
X300322Y466936D01*
X300572Y467019D01*
X300822Y466936D01*
X301030Y466728D01*
X301155Y466353D01*
X301113Y465978D01*
X300947Y465603D01*
G01X509525Y650833D02*
X509192Y650625D01*
X508817Y650500D01*
X508483D01*
X508150Y650625D01*
X507900Y650833D01*
X507775Y651125D01*
X507858Y651417D01*
X508067Y651667D01*
X508442Y651833D01*
X508942Y651917D01*
X509233Y652083D01*
X509358Y652375D01*
X509275Y652667D01*
X509067Y652875D01*
X508775Y653000D01*
X508483D01*
X508192Y652917D01*
X507942Y652708D01*
G01X504633Y652792D02*
X504883Y652917D01*
X505175Y653000D01*
X505508D01*
X505883Y652875D01*
X506175Y652667D01*
X506383Y652417D01*
X506550Y652000D01*
X506592Y651625D01*
X506508Y651250D01*
X506383Y651000D01*
X506133Y650750D01*
X505842Y650583D01*
X505550Y650500D01*
X505258D01*
X504967Y650583D01*
X504717Y650708D01*
X504508Y650875D01*
G01X503700Y653000D02*
X503117Y650500D01*
X502450Y653000D01*
X501783Y650500D01*
X501200Y653000D01*
G01X499350Y650500D02*
Y653000D01*
X499850Y652500D01*
G01Y650500D02*
X498850D01*
G01X527392Y1423234D02*
X529892D01*
Y1424275D01*
X529767Y1424609D01*
X529600Y1424817D01*
X529267Y1424900D01*
X528934Y1424817D01*
X528725Y1424567D01*
X528600Y1424275D01*
Y1423234D01*
G01Y1424275D02*
X527392Y1424900D01*
G01X527684Y1426459D02*
X527475Y1426750D01*
X527392Y1427084D01*
X527475Y1427417D01*
X527725Y1427709D01*
X528100Y1427917D01*
X528475Y1428000D01*
X528934D01*
X529309Y1427917D01*
X529642Y1427709D01*
X529809Y1427459D01*
X529892Y1427167D01*
X529809Y1426834D01*
X529642Y1426584D01*
X529392Y1426417D01*
X529059Y1426334D01*
X528767Y1426417D01*
X528475Y1426625D01*
X528309Y1426875D01*
X528267Y1427167D01*
X528350Y1427500D01*
X528559Y1427750D01*
X528934Y1428000D01*
G01X528434Y1429475D02*
X528725Y1429767D01*
X528892Y1430017D01*
X528975Y1430350D01*
X528892Y1430642D01*
X528725Y1430850D01*
X528475Y1431017D01*
X528184Y1431059D01*
X527934Y1431017D01*
X527684Y1430850D01*
X527475Y1430600D01*
X527392Y1430309D01*
X527475Y1429975D01*
X527725Y1429684D01*
X528100Y1429517D01*
X528517Y1429475D01*
X529059Y1429559D01*
X529350Y1429684D01*
X529642Y1429892D01*
X529850Y1430184D01*
X529892Y1430475D01*
X529809Y1430767D01*
X529600Y1430975D01*
G01X528434Y1432575D02*
X528725Y1432867D01*
X528892Y1433117D01*
X528975Y1433450D01*
X528892Y1433742D01*
X528725Y1433950D01*
X528475Y1434117D01*
X528184Y1434159D01*
X527934Y1434117D01*
X527684Y1433950D01*
X527475Y1433700D01*
X527392Y1433409D01*
X527475Y1433075D01*
X527725Y1432784D01*
X528100Y1432617D01*
X528517Y1432575D01*
X529059Y1432659D01*
X529350Y1432784D01*
X529642Y1432992D01*
X529850Y1433284D01*
X529892Y1433575D01*
X529809Y1433867D01*
X529600Y1434075D01*
G01X523392Y1423234D02*
X525892D01*
Y1424275D01*
X525767Y1424609D01*
X525600Y1424817D01*
X525267Y1424900D01*
X524934Y1424817D01*
X524725Y1424567D01*
X524600Y1424275D01*
Y1423234D01*
G01Y1424275D02*
X523392Y1424900D01*
G01Y1427167D02*
X525892D01*
X525392Y1426667D01*
G01X523392D02*
Y1427667D01*
G01Y1430767D02*
X525892D01*
X524100Y1429225D01*
Y1431309D01*
G01X523392Y1433867D02*
X525892D01*
X524100Y1432325D01*
Y1434409D01*
G01X498199Y1442055D02*
Y1425955D01*
G01X505199D02*
Y1442055D01*
G01X498199Y1425955D02*
X505199D01*
G01X517231Y1413987D02*
X517564Y1414029D01*
X517856Y1414195D01*
X518106Y1414445D01*
X518273Y1414737D01*
X518356Y1415070D01*
Y1415404D01*
X518273Y1415737D01*
X518106Y1416029D01*
X517856Y1416279D01*
X517564Y1416445D01*
X517231Y1416487D01*
X516898Y1416445D01*
X516606Y1416279D01*
X516356Y1416029D01*
X516189Y1415737D01*
X516106Y1415404D01*
Y1415070D01*
X516189Y1414737D01*
X516356Y1414445D01*
X516606Y1414195D01*
X516898Y1414029D01*
X517231Y1413987D01*
G01X516898Y1414654D02*
X516398Y1413987D01*
G01X514923Y1416070D02*
X514673Y1416320D01*
X514381Y1416445D01*
X514048Y1416487D01*
X513631Y1416404D01*
X513339Y1416195D01*
X513256Y1415945D01*
X513298Y1415695D01*
X513464Y1415487D01*
X514298Y1415070D01*
X514673Y1414779D01*
X514923Y1414362D01*
X515006Y1413987D01*
X513256D01*
G01X511031D02*
Y1416487D01*
X511531Y1415987D01*
G01Y1413987D02*
X510531D01*
G01X508723Y1416070D02*
X508473Y1416320D01*
X508181Y1416445D01*
X507848Y1416487D01*
X507431Y1416404D01*
X507139Y1416195D01*
X507056Y1415945D01*
X507098Y1415695D01*
X507264Y1415487D01*
X508098Y1415070D01*
X508473Y1414779D01*
X508723Y1414362D01*
X508806Y1413987D01*
X507056D01*
G01X519299Y1432355D02*
Y1418355D01*
G01X506299D02*
Y1432355D01*
G01X519299Y1418355D02*
X506299D01*
G01X530383Y1443665D02*
X530633Y1443790D01*
X530925Y1443873D01*
X531258D01*
X531633Y1443748D01*
X531925Y1443540D01*
X532133Y1443290D01*
X532300Y1442873D01*
X532342Y1442498D01*
X532258Y1442123D01*
X532133Y1441873D01*
X531883Y1441623D01*
X531592Y1441456D01*
X531300Y1441373D01*
X531008D01*
X530717Y1441456D01*
X530467Y1441581D01*
X530258Y1441748D01*
G01X529117Y1441873D02*
X528867Y1441581D01*
X528533Y1441415D01*
X528158Y1441373D01*
X527825Y1441415D01*
X527492Y1441623D01*
X527283Y1441873D01*
X527242Y1442123D01*
X527325Y1442415D01*
X527617Y1442623D01*
X527908Y1442706D01*
X528283D01*
G01X527908D02*
X527658Y1442831D01*
X527450Y1443040D01*
X527367Y1443290D01*
X527450Y1443540D01*
X527658Y1443748D01*
X528033Y1443873D01*
X528408Y1443831D01*
X528783Y1443665D01*
G01X525183Y1441373D02*
X525100Y1441915D01*
X524975Y1442373D01*
X524808Y1442790D01*
X524600Y1443248D01*
X524267Y1443873D01*
X525933D01*
G01X522000Y1441373D02*
X521708Y1441415D01*
X521375Y1441540D01*
X521167Y1441748D01*
X521083Y1442040D01*
X521167Y1442331D01*
X521417Y1442581D01*
X521792Y1442706D01*
X522208D01*
X522458Y1442790D01*
X522667Y1442998D01*
X522750Y1443290D01*
X522625Y1443581D01*
X522333Y1443790D01*
X522000Y1443873D01*
X521667Y1443790D01*
X521375Y1443581D01*
X521250Y1443290D01*
X521333Y1442998D01*
X521542Y1442790D01*
X521792Y1442706D01*
X522208D01*
X522583Y1442581D01*
X522833Y1442331D01*
X522917Y1442040D01*
X522833Y1441748D01*
X522625Y1441540D01*
X522292Y1441415D01*
X522000Y1441373D01*
G01X514898Y1440421D02*
X518898D01*
Y1433021D01*
G01X514849Y1433055D02*
X510849D01*
Y1440455D01*
G01X494299Y1430038D02*
X496799D01*
Y1430872D01*
X496674Y1431205D01*
X496507Y1431455D01*
X496257Y1431663D01*
X495966Y1431830D01*
X495549Y1431872D01*
X495132Y1431830D01*
X494841Y1431663D01*
X494591Y1431455D01*
X494424Y1431205D01*
X494299Y1430872D01*
Y1430038D01*
G01X494674Y1433138D02*
X494466Y1433388D01*
X494341Y1433680D01*
X494299Y1434055D01*
X494382Y1434430D01*
X494549Y1434722D01*
X494841Y1434930D01*
X495174Y1434972D01*
X495507Y1434888D01*
X495716Y1434680D01*
X495882Y1434388D01*
X495924Y1434097D01*
X495882Y1433805D01*
X495716Y1433430D01*
X496799Y1433555D01*
Y1434680D01*
G01Y1437155D02*
X496716Y1436822D01*
X496507Y1436572D01*
X496257Y1436405D01*
X495924Y1436280D01*
X495549Y1436238D01*
X495174Y1436280D01*
X494841Y1436405D01*
X494591Y1436572D01*
X494382Y1436822D01*
X494299Y1437155D01*
X494382Y1437488D01*
X494591Y1437738D01*
X494841Y1437905D01*
X495174Y1438030D01*
X495549Y1438072D01*
X495924Y1438030D01*
X496257Y1437905D01*
X496507Y1437738D01*
X496716Y1437488D01*
X496799Y1437155D01*
G01X505199Y1442055D02*
X498199D01*
G01X506299Y1432355D02*
X519299D01*
G01X670462Y1473367D02*
X670587Y1473117D01*
X670670Y1472825D01*
Y1472492D01*
X670545Y1472117D01*
X670337Y1471825D01*
X670087Y1471617D01*
X669670Y1471450D01*
X669295Y1471408D01*
X668920Y1471492D01*
X668670Y1471617D01*
X668420Y1471867D01*
X668253Y1472158D01*
X668170Y1472450D01*
Y1472742D01*
X668253Y1473033D01*
X668378Y1473283D01*
X668545Y1473492D01*
G01Y1474633D02*
X668337Y1474883D01*
X668212Y1475175D01*
X668170Y1475550D01*
X668253Y1475925D01*
X668420Y1476217D01*
X668712Y1476425D01*
X669045Y1476467D01*
X669378Y1476383D01*
X669587Y1476175D01*
X669753Y1475883D01*
X669795Y1475592D01*
X669753Y1475300D01*
X669587Y1474925D01*
X670670Y1475050D01*
Y1476175D01*
G01X668170Y1479150D02*
X670670D01*
X668878Y1477608D01*
Y1479692D01*
G01X668670Y1480833D02*
X668378Y1481083D01*
X668212Y1481417D01*
X668170Y1481792D01*
X668212Y1482125D01*
X668420Y1482458D01*
X668670Y1482667D01*
X668920Y1482708D01*
X669212Y1482625D01*
X669420Y1482333D01*
X669503Y1482042D01*
Y1481667D01*
G01Y1482042D02*
X669628Y1482292D01*
X669837Y1482500D01*
X670087Y1482583D01*
X670337Y1482500D01*
X670545Y1482292D01*
X670670Y1481917D01*
X670628Y1481542D01*
X670462Y1481167D01*
G01X664083Y1479600D02*
Y1482100D01*
X663042D01*
X662708Y1481975D01*
X662500Y1481808D01*
X662417Y1481475D01*
X662500Y1481142D01*
X662750Y1480933D01*
X663042Y1480808D01*
X664083D01*
G01X663042D02*
X662417Y1479600D01*
G01X660858Y1479892D02*
X660567Y1479683D01*
X660233Y1479600D01*
X659900Y1479683D01*
X659608Y1479933D01*
X659400Y1480308D01*
X659317Y1480683D01*
Y1481142D01*
X659400Y1481517D01*
X659608Y1481850D01*
X659858Y1482017D01*
X660150Y1482100D01*
X660483Y1482017D01*
X660733Y1481850D01*
X660900Y1481600D01*
X660983Y1481267D01*
X660900Y1480975D01*
X660692Y1480683D01*
X660442Y1480517D01*
X660150Y1480475D01*
X659817Y1480558D01*
X659567Y1480767D01*
X659317Y1481142D01*
G01X657758Y1479892D02*
X657467Y1479683D01*
X657133Y1479600D01*
X656800Y1479683D01*
X656508Y1479933D01*
X656300Y1480308D01*
X656217Y1480683D01*
Y1481142D01*
X656300Y1481517D01*
X656508Y1481850D01*
X656758Y1482017D01*
X657050Y1482100D01*
X657383Y1482017D01*
X657633Y1481850D01*
X657800Y1481600D01*
X657883Y1481267D01*
X657800Y1480975D01*
X657592Y1480683D01*
X657342Y1480517D01*
X657050Y1480475D01*
X656717Y1480558D01*
X656467Y1480767D01*
X656217Y1481142D01*
G01X654658Y1479892D02*
X654367Y1479683D01*
X654033Y1479600D01*
X653700Y1479683D01*
X653408Y1479933D01*
X653200Y1480308D01*
X653117Y1480683D01*
Y1481142D01*
X653200Y1481517D01*
X653408Y1481850D01*
X653658Y1482017D01*
X653950Y1482100D01*
X654283Y1482017D01*
X654533Y1481850D01*
X654700Y1481600D01*
X654783Y1481267D01*
X654700Y1480975D01*
X654492Y1480683D01*
X654242Y1480517D01*
X653950Y1480475D01*
X653617Y1480558D01*
X653367Y1480767D01*
X653117Y1481142D01*
G01X656600Y1462000D02*
Y1466000D01*
X664000D01*
G01X664083Y1483600D02*
Y1486100D01*
X663042D01*
X662708Y1485975D01*
X662500Y1485808D01*
X662417Y1485475D01*
X662500Y1485142D01*
X662750Y1484933D01*
X663042Y1484808D01*
X664083D01*
G01X663042D02*
X662417Y1483600D01*
G01X660858Y1483892D02*
X660567Y1483683D01*
X660233Y1483600D01*
X659900Y1483683D01*
X659608Y1483933D01*
X659400Y1484308D01*
X659317Y1484683D01*
Y1485142D01*
X659400Y1485517D01*
X659608Y1485850D01*
X659858Y1486017D01*
X660150Y1486100D01*
X660483Y1486017D01*
X660733Y1485850D01*
X660900Y1485600D01*
X660983Y1485267D01*
X660900Y1484975D01*
X660692Y1484683D01*
X660442Y1484517D01*
X660150Y1484475D01*
X659817Y1484558D01*
X659567Y1484767D01*
X659317Y1485142D01*
G01X657758Y1483892D02*
X657467Y1483683D01*
X657133Y1483600D01*
X656800Y1483683D01*
X656508Y1483933D01*
X656300Y1484308D01*
X656217Y1484683D01*
Y1485142D01*
X656300Y1485517D01*
X656508Y1485850D01*
X656758Y1486017D01*
X657050Y1486100D01*
X657383Y1486017D01*
X657633Y1485850D01*
X657800Y1485600D01*
X657883Y1485267D01*
X657800Y1484975D01*
X657592Y1484683D01*
X657342Y1484517D01*
X657050Y1484475D01*
X656717Y1484558D01*
X656467Y1484767D01*
X656217Y1485142D01*
G01X654742Y1484642D02*
X654450Y1484933D01*
X654200Y1485100D01*
X653867Y1485183D01*
X653575Y1485100D01*
X653367Y1484933D01*
X653200Y1484683D01*
X653158Y1484392D01*
X653200Y1484142D01*
X653367Y1483892D01*
X653617Y1483683D01*
X653908Y1483600D01*
X654242Y1483683D01*
X654533Y1483933D01*
X654700Y1484308D01*
X654742Y1484725D01*
X654658Y1485267D01*
X654533Y1485558D01*
X654325Y1485850D01*
X654033Y1486058D01*
X653742Y1486100D01*
X653450Y1486017D01*
X653242Y1485808D01*
G01X656600Y1466000D02*
Y1470000D01*
X664000D01*
G01X664083Y1471500D02*
Y1474000D01*
X663042D01*
X662708Y1473875D01*
X662500Y1473708D01*
X662417Y1473375D01*
X662500Y1473042D01*
X662750Y1472833D01*
X663042Y1472708D01*
X664083D01*
G01X663042D02*
X662417Y1471500D01*
G01X660150D02*
Y1474000D01*
X660650Y1473500D01*
G01Y1471500D02*
X659650D01*
G01X657050Y1474000D02*
X657383Y1473917D01*
X657633Y1473708D01*
X657800Y1473458D01*
X657925Y1473125D01*
X657967Y1472750D01*
X657925Y1472375D01*
X657800Y1472042D01*
X657633Y1471792D01*
X657383Y1471583D01*
X657050Y1471500D01*
X656717Y1471583D01*
X656467Y1471792D01*
X656300Y1472042D01*
X656175Y1472375D01*
X656133Y1472750D01*
X656175Y1473125D01*
X656300Y1473458D01*
X656467Y1473708D01*
X656717Y1473917D01*
X657050Y1474000D01*
G01X654867Y1471875D02*
X654617Y1471667D01*
X654325Y1471542D01*
X653950Y1471500D01*
X653575Y1471583D01*
X653283Y1471750D01*
X653075Y1472042D01*
X653033Y1472375D01*
X653117Y1472708D01*
X653325Y1472917D01*
X653617Y1473083D01*
X653908Y1473125D01*
X654200Y1473083D01*
X654575Y1472917D01*
X654450Y1474000D01*
X653325D01*
G01X651558Y1471792D02*
X651267Y1471583D01*
X650933Y1471500D01*
X650600Y1471583D01*
X650308Y1471833D01*
X650100Y1472208D01*
X650017Y1472583D01*
Y1473042D01*
X650100Y1473417D01*
X650308Y1473750D01*
X650558Y1473917D01*
X650850Y1474000D01*
X651183Y1473917D01*
X651433Y1473750D01*
X651600Y1473500D01*
X651683Y1473167D01*
X651600Y1472875D01*
X651392Y1472583D01*
X651142Y1472417D01*
X650850Y1472375D01*
X650517Y1472458D01*
X650267Y1472667D01*
X650017Y1473042D01*
G01X656600Y1451500D02*
Y1455500D01*
X664000D01*
G01X664083Y1475500D02*
Y1478000D01*
X663042D01*
X662708Y1477875D01*
X662500Y1477708D01*
X662417Y1477375D01*
X662500Y1477042D01*
X662750Y1476833D01*
X663042Y1476708D01*
X664083D01*
G01X663042D02*
X662417Y1475500D01*
G01X660150D02*
Y1478000D01*
X660650Y1477500D01*
G01Y1475500D02*
X659650D01*
G01X657050Y1478000D02*
X657383Y1477917D01*
X657633Y1477708D01*
X657800Y1477458D01*
X657925Y1477125D01*
X657967Y1476750D01*
X657925Y1476375D01*
X657800Y1476042D01*
X657633Y1475792D01*
X657383Y1475583D01*
X657050Y1475500D01*
X656717Y1475583D01*
X656467Y1475792D01*
X656300Y1476042D01*
X656175Y1476375D01*
X656133Y1476750D01*
X656175Y1477125D01*
X656300Y1477458D01*
X656467Y1477708D01*
X656717Y1477917D01*
X657050Y1478000D01*
G01X654867Y1476000D02*
X654617Y1475708D01*
X654283Y1475542D01*
X653908Y1475500D01*
X653575Y1475542D01*
X653242Y1475750D01*
X653033Y1476000D01*
X652992Y1476250D01*
X653075Y1476542D01*
X653367Y1476750D01*
X653658Y1476833D01*
X654033D01*
G01X653658D02*
X653408Y1476958D01*
X653200Y1477167D01*
X653117Y1477417D01*
X653200Y1477667D01*
X653408Y1477875D01*
X653783Y1478000D01*
X654158Y1477958D01*
X654533Y1477792D01*
G01X651642Y1477583D02*
X651392Y1477833D01*
X651100Y1477958D01*
X650767Y1478000D01*
X650350Y1477917D01*
X650058Y1477708D01*
X649975Y1477458D01*
X650017Y1477208D01*
X650183Y1477000D01*
X651017Y1476583D01*
X651392Y1476292D01*
X651642Y1475875D01*
X651725Y1475500D01*
X649975D01*
G01X656600Y1455500D02*
Y1459500D01*
X664000D01*
G01X720133Y1458192D02*
X720383Y1458317D01*
X720675Y1458400D01*
X721008D01*
X721383Y1458275D01*
X721675Y1458067D01*
X721883Y1457817D01*
X722050Y1457400D01*
X722092Y1457025D01*
X722008Y1456650D01*
X721883Y1456400D01*
X721633Y1456150D01*
X721342Y1455983D01*
X721050Y1455900D01*
X720758D01*
X720467Y1455983D01*
X720217Y1456108D01*
X720008Y1456275D01*
G01X718867D02*
X718617Y1456067D01*
X718325Y1455942D01*
X717950Y1455900D01*
X717575Y1455983D01*
X717283Y1456150D01*
X717075Y1456442D01*
X717033Y1456775D01*
X717117Y1457108D01*
X717325Y1457317D01*
X717617Y1457483D01*
X717908Y1457525D01*
X718200Y1457483D01*
X718575Y1457317D01*
X718450Y1458400D01*
X717325D01*
G01X714350Y1455900D02*
Y1458400D01*
X715892Y1456608D01*
X713808D01*
G01X711250Y1455900D02*
Y1458400D01*
X712792Y1456608D01*
X710708D01*
G01X859796Y1309166D02*
X859921Y1308916D01*
X860004Y1308624D01*
Y1308291D01*
X859879Y1307916D01*
X859671Y1307624D01*
X859421Y1307416D01*
X859004Y1307249D01*
X858629Y1307207D01*
X858254Y1307291D01*
X858004Y1307416D01*
X857754Y1307666D01*
X857587Y1307957D01*
X857504Y1308249D01*
Y1308541D01*
X857587Y1308832D01*
X857712Y1309082D01*
X857879Y1309291D01*
G01Y1310432D02*
X857671Y1310682D01*
X857546Y1310974D01*
X857504Y1311349D01*
X857587Y1311724D01*
X857754Y1312016D01*
X858046Y1312224D01*
X858379Y1312266D01*
X858712Y1312182D01*
X858921Y1311974D01*
X859087Y1311682D01*
X859129Y1311391D01*
X859087Y1311099D01*
X858921Y1310724D01*
X860004Y1310849D01*
Y1311974D01*
G01X858546Y1313657D02*
X858837Y1313949D01*
X859004Y1314199D01*
X859087Y1314532D01*
X859004Y1314824D01*
X858837Y1315032D01*
X858587Y1315199D01*
X858296Y1315241D01*
X858046Y1315199D01*
X857796Y1315032D01*
X857587Y1314782D01*
X857504Y1314491D01*
X857587Y1314157D01*
X857837Y1313866D01*
X858212Y1313699D01*
X858629Y1313657D01*
X859171Y1313741D01*
X859462Y1313866D01*
X859754Y1314074D01*
X859962Y1314366D01*
X860004Y1314657D01*
X859921Y1314949D01*
X859712Y1315157D01*
G01X857504Y1317549D02*
X857546Y1317841D01*
X857671Y1318174D01*
X857879Y1318382D01*
X858171Y1318466D01*
X858462Y1318382D01*
X858712Y1318132D01*
X858837Y1317757D01*
Y1317341D01*
X858921Y1317091D01*
X859129Y1316882D01*
X859421Y1316799D01*
X859712Y1316924D01*
X859921Y1317216D01*
X860004Y1317549D01*
X859921Y1317882D01*
X859712Y1318174D01*
X859421Y1318299D01*
X859129Y1318216D01*
X858921Y1318007D01*
X858837Y1317757D01*
Y1317341D01*
X858712Y1316966D01*
X858462Y1316716D01*
X858171Y1316632D01*
X857879Y1316716D01*
X857671Y1316924D01*
X857546Y1317257D01*
X857504Y1317549D01*
G01X864236Y1286150D02*
Y1304850D01*
X853936D01*
Y1286150D01*
X864236D01*
G01X802650Y1293000D02*
X802983Y1293042D01*
X803275Y1293208D01*
X803525Y1293458D01*
X803692Y1293750D01*
X803775Y1294083D01*
Y1294417D01*
X803692Y1294750D01*
X803525Y1295042D01*
X803275Y1295292D01*
X802983Y1295458D01*
X802650Y1295500D01*
X802317Y1295458D01*
X802025Y1295292D01*
X801775Y1295042D01*
X801608Y1294750D01*
X801525Y1294417D01*
Y1294083D01*
X801608Y1293750D01*
X801775Y1293458D01*
X802025Y1293208D01*
X802317Y1293042D01*
X802650Y1293000D01*
G01X802317Y1293667D02*
X801817Y1293000D01*
G01X799550D02*
Y1295500D01*
X800050Y1295000D01*
G01Y1293000D02*
X799050D01*
G01X797158Y1293292D02*
X796867Y1293083D01*
X796533Y1293000D01*
X796200Y1293083D01*
X795908Y1293333D01*
X795700Y1293708D01*
X795617Y1294083D01*
Y1294542D01*
X795700Y1294917D01*
X795908Y1295250D01*
X796158Y1295417D01*
X796450Y1295500D01*
X796783Y1295417D01*
X797033Y1295250D01*
X797200Y1295000D01*
X797283Y1294667D01*
X797200Y1294375D01*
X796992Y1294083D01*
X796742Y1293917D01*
X796450Y1293875D01*
X796117Y1293958D01*
X795867Y1294167D01*
X795617Y1294542D01*
G01X792850Y1293000D02*
Y1295500D01*
X794392Y1293708D01*
X792308D01*
G01X813631Y1323985D02*
X783631D01*
Y1301185D01*
X813631D01*
Y1323985D01*
G01X836533Y1331500D02*
Y1334000D01*
X835492D01*
X835158Y1333875D01*
X834950Y1333708D01*
X834867Y1333375D01*
X834950Y1333042D01*
X835200Y1332833D01*
X835492Y1332708D01*
X836533D01*
G01X835492D02*
X834867Y1331500D01*
G01X832600D02*
Y1334000D01*
X833100Y1333500D01*
G01Y1331500D02*
X832100D01*
G01X829500Y1334000D02*
X829833Y1333917D01*
X830083Y1333708D01*
X830250Y1333458D01*
X830375Y1333125D01*
X830417Y1332750D01*
X830375Y1332375D01*
X830250Y1332042D01*
X830083Y1331792D01*
X829833Y1331583D01*
X829500Y1331500D01*
X829167Y1331583D01*
X828917Y1331792D01*
X828750Y1332042D01*
X828625Y1332375D01*
X828583Y1332750D01*
X828625Y1333125D01*
X828750Y1333458D01*
X828917Y1333708D01*
X829167Y1333917D01*
X829500Y1334000D01*
G01X826400Y1331500D02*
Y1334000D01*
X826900Y1333500D01*
G01Y1331500D02*
X825900D01*
G01X823383D02*
X823300Y1332042D01*
X823175Y1332500D01*
X823008Y1332917D01*
X822800Y1333375D01*
X822467Y1334000D01*
X824133D01*
G01X807300Y1329500D02*
X812500D01*
G01X807300D02*
Y1336500D01*
G01X820700Y1329500D02*
X812000D01*
G01X820700Y1336500D02*
Y1329500D01*
G01X840033Y1295000D02*
Y1297500D01*
X838992D01*
X838658Y1297375D01*
X838450Y1297208D01*
X838367Y1296875D01*
X838450Y1296542D01*
X838700Y1296333D01*
X838992Y1296208D01*
X840033D01*
G01X838992D02*
X838367Y1295000D01*
G01X836100D02*
Y1297500D01*
X836600Y1297000D01*
G01Y1295000D02*
X835600D01*
G01X833000Y1297500D02*
X833333Y1297417D01*
X833583Y1297208D01*
X833750Y1296958D01*
X833875Y1296625D01*
X833917Y1296250D01*
X833875Y1295875D01*
X833750Y1295542D01*
X833583Y1295292D01*
X833333Y1295083D01*
X833000Y1295000D01*
X832667Y1295083D01*
X832417Y1295292D01*
X832250Y1295542D01*
X832125Y1295875D01*
X832083Y1296250D01*
X832125Y1296625D01*
X832250Y1296958D01*
X832417Y1297208D01*
X832667Y1297417D01*
X833000Y1297500D01*
G01X829900Y1295000D02*
Y1297500D01*
X830400Y1297000D01*
G01Y1295000D02*
X829400D01*
G01X827717Y1295375D02*
X827467Y1295167D01*
X827175Y1295042D01*
X826800Y1295000D01*
X826425Y1295083D01*
X826133Y1295250D01*
X825925Y1295542D01*
X825883Y1295875D01*
X825967Y1296208D01*
X826175Y1296417D01*
X826467Y1296583D01*
X826758Y1296625D01*
X827050Y1296583D01*
X827425Y1296417D01*
X827300Y1297500D01*
X826175D01*
G01X807300Y1292500D02*
X812500D01*
G01X807300Y1299500D02*
X815100D01*
G01X807300Y1292500D02*
Y1299500D01*
G01X820700Y1292500D02*
X812000D01*
G01X820700Y1299500D02*
Y1292500D01*
G01X814300Y1299500D02*
X820700D01*
G01X843151Y1413424D02*
X843276Y1413174D01*
X843359Y1412882D01*
Y1412549D01*
X843234Y1412174D01*
X843026Y1411882D01*
X842776Y1411674D01*
X842359Y1411507D01*
X841984Y1411465D01*
X841609Y1411549D01*
X841359Y1411674D01*
X841109Y1411924D01*
X840942Y1412215D01*
X840859Y1412507D01*
Y1412799D01*
X840942Y1413090D01*
X841067Y1413340D01*
X841234Y1413549D01*
G01Y1414690D02*
X841026Y1414940D01*
X840901Y1415232D01*
X840859Y1415607D01*
X840942Y1415982D01*
X841109Y1416274D01*
X841401Y1416482D01*
X841734Y1416524D01*
X842067Y1416440D01*
X842276Y1416232D01*
X842442Y1415940D01*
X842484Y1415649D01*
X842442Y1415357D01*
X842276Y1414982D01*
X843359Y1415107D01*
Y1416232D01*
G01X840859Y1418707D02*
X843359D01*
X842859Y1418207D01*
G01X840859D02*
Y1419207D01*
G01Y1421807D02*
X843359D01*
X842859Y1421307D01*
G01X840859D02*
Y1422307D01*
G01X837350Y1408850D02*
Y1390150D01*
X847650D01*
Y1408850D01*
X837350D01*
G01X862514Y1414462D02*
X862639Y1414212D01*
X862722Y1413920D01*
Y1413587D01*
X862597Y1413212D01*
X862389Y1412920D01*
X862139Y1412712D01*
X861722Y1412545D01*
X861347Y1412503D01*
X860972Y1412587D01*
X860722Y1412712D01*
X860472Y1412962D01*
X860305Y1413253D01*
X860222Y1413545D01*
Y1413837D01*
X860305Y1414128D01*
X860430Y1414378D01*
X860597Y1414587D01*
G01Y1415728D02*
X860389Y1415978D01*
X860264Y1416270D01*
X860222Y1416645D01*
X860305Y1417020D01*
X860472Y1417312D01*
X860764Y1417520D01*
X861097Y1417562D01*
X861430Y1417478D01*
X861639Y1417270D01*
X861805Y1416978D01*
X861847Y1416687D01*
X861805Y1416395D01*
X861639Y1416020D01*
X862722Y1416145D01*
Y1417270D01*
G01X860222Y1419745D02*
X862722D01*
X862222Y1419245D01*
G01X860222D02*
Y1420245D01*
G01X860597Y1421928D02*
X860389Y1422178D01*
X860264Y1422470D01*
X860222Y1422845D01*
X860305Y1423220D01*
X860472Y1423512D01*
X860764Y1423720D01*
X861097Y1423762D01*
X861430Y1423678D01*
X861639Y1423470D01*
X861805Y1423178D01*
X861847Y1422887D01*
X861805Y1422595D01*
X861639Y1422220D01*
X862722Y1422345D01*
Y1423470D01*
G01X854850Y1408850D02*
Y1390150D01*
X865150D01*
Y1408850D01*
X854850D01*
G01X803650Y1368000D02*
X803983Y1368042D01*
X804275Y1368208D01*
X804525Y1368458D01*
X804692Y1368750D01*
X804775Y1369083D01*
Y1369417D01*
X804692Y1369750D01*
X804525Y1370042D01*
X804275Y1370292D01*
X803983Y1370458D01*
X803650Y1370500D01*
X803317Y1370458D01*
X803025Y1370292D01*
X802775Y1370042D01*
X802608Y1369750D01*
X802525Y1369417D01*
Y1369083D01*
X802608Y1368750D01*
X802775Y1368458D01*
X803025Y1368208D01*
X803317Y1368042D01*
X803650Y1368000D01*
G01X803317Y1368667D02*
X802817Y1368000D01*
G01X800550D02*
Y1370500D01*
X801050Y1370000D01*
G01Y1368000D02*
X800050D01*
G01X798158Y1368292D02*
X797867Y1368083D01*
X797533Y1368000D01*
X797200Y1368083D01*
X796908Y1368333D01*
X796700Y1368708D01*
X796617Y1369083D01*
Y1369542D01*
X796700Y1369917D01*
X796908Y1370250D01*
X797158Y1370417D01*
X797450Y1370500D01*
X797783Y1370417D01*
X798033Y1370250D01*
X798200Y1370000D01*
X798283Y1369667D01*
X798200Y1369375D01*
X797992Y1369083D01*
X797742Y1368917D01*
X797450Y1368875D01*
X797117Y1368958D01*
X796867Y1369167D01*
X796617Y1369542D01*
G01X795142Y1369042D02*
X794850Y1369333D01*
X794600Y1369500D01*
X794267Y1369583D01*
X793975Y1369500D01*
X793767Y1369333D01*
X793600Y1369083D01*
X793558Y1368792D01*
X793600Y1368542D01*
X793767Y1368292D01*
X794017Y1368083D01*
X794308Y1368000D01*
X794642Y1368083D01*
X794933Y1368333D01*
X795100Y1368708D01*
X795142Y1369125D01*
X795058Y1369667D01*
X794933Y1369958D01*
X794725Y1370250D01*
X794433Y1370458D01*
X794142Y1370500D01*
X793850Y1370417D01*
X793642Y1370208D01*
G01X814101Y1366491D02*
X784101D01*
Y1343691D01*
X814101D01*
Y1366491D01*
G01X813450Y1406800D02*
X813783Y1406842D01*
X814075Y1407008D01*
X814325Y1407258D01*
X814492Y1407550D01*
X814575Y1407883D01*
Y1408217D01*
X814492Y1408550D01*
X814325Y1408842D01*
X814075Y1409092D01*
X813783Y1409258D01*
X813450Y1409300D01*
X813117Y1409258D01*
X812825Y1409092D01*
X812575Y1408842D01*
X812408Y1408550D01*
X812325Y1408217D01*
Y1407883D01*
X812408Y1407550D01*
X812575Y1407258D01*
X812825Y1407008D01*
X813117Y1406842D01*
X813450Y1406800D01*
G01X813117Y1407467D02*
X812617Y1406800D01*
G01X810350D02*
Y1409300D01*
X810850Y1408800D01*
G01Y1406800D02*
X809850D01*
G01X807958Y1407092D02*
X807667Y1406883D01*
X807333Y1406800D01*
X807000Y1406883D01*
X806708Y1407133D01*
X806500Y1407508D01*
X806417Y1407883D01*
Y1408342D01*
X806500Y1408717D01*
X806708Y1409050D01*
X806958Y1409217D01*
X807250Y1409300D01*
X807583Y1409217D01*
X807833Y1409050D01*
X808000Y1408800D01*
X808083Y1408467D01*
X808000Y1408175D01*
X807792Y1407883D01*
X807542Y1407717D01*
X807250Y1407675D01*
X806917Y1407758D01*
X806667Y1407967D01*
X806417Y1408342D01*
G01X804150Y1406800D02*
X803858Y1406842D01*
X803525Y1406967D01*
X803317Y1407175D01*
X803233Y1407467D01*
X803317Y1407758D01*
X803567Y1408008D01*
X803942Y1408133D01*
X804358D01*
X804608Y1408217D01*
X804817Y1408425D01*
X804900Y1408717D01*
X804775Y1409008D01*
X804483Y1409217D01*
X804150Y1409300D01*
X803817Y1409217D01*
X803525Y1409008D01*
X803400Y1408717D01*
X803483Y1408425D01*
X803692Y1408217D01*
X803942Y1408133D01*
X804358D01*
X804733Y1408008D01*
X804983Y1407758D01*
X805067Y1407467D01*
X804983Y1407175D01*
X804775Y1406967D01*
X804442Y1406842D01*
X804150Y1406800D01*
G01X813880Y1404159D02*
X783880D01*
Y1381359D01*
X813880D01*
Y1404159D01*
G01X839533Y1370500D02*
Y1373000D01*
X838492D01*
X838158Y1372875D01*
X837950Y1372708D01*
X837867Y1372375D01*
X837950Y1372042D01*
X838200Y1371833D01*
X838492Y1371708D01*
X839533D01*
G01X838492D02*
X837867Y1370500D01*
G01X835600D02*
Y1373000D01*
X836100Y1372500D01*
G01Y1370500D02*
X835100D01*
G01X832500Y1373000D02*
X832833Y1372917D01*
X833083Y1372708D01*
X833250Y1372458D01*
X833375Y1372125D01*
X833417Y1371750D01*
X833375Y1371375D01*
X833250Y1371042D01*
X833083Y1370792D01*
X832833Y1370583D01*
X832500Y1370500D01*
X832167Y1370583D01*
X831917Y1370792D01*
X831750Y1371042D01*
X831625Y1371375D01*
X831583Y1371750D01*
X831625Y1372125D01*
X831750Y1372458D01*
X831917Y1372708D01*
X832167Y1372917D01*
X832500Y1373000D01*
G01X829400Y1370500D02*
Y1373000D01*
X829900Y1372500D01*
G01Y1370500D02*
X828900D01*
G01X827008Y1370792D02*
X826717Y1370583D01*
X826383Y1370500D01*
X826050Y1370583D01*
X825758Y1370833D01*
X825550Y1371208D01*
X825467Y1371583D01*
Y1372042D01*
X825550Y1372417D01*
X825758Y1372750D01*
X826008Y1372917D01*
X826300Y1373000D01*
X826633Y1372917D01*
X826883Y1372750D01*
X827050Y1372500D01*
X827133Y1372167D01*
X827050Y1371875D01*
X826842Y1371583D01*
X826592Y1371417D01*
X826300Y1371375D01*
X825967Y1371458D01*
X825717Y1371667D01*
X825467Y1372042D01*
G01X807300Y1368000D02*
X812500D01*
G01X807300Y1375000D02*
X815100D01*
G01X807300Y1368000D02*
Y1375000D01*
G01X820700Y1368000D02*
X812000D01*
G01X820700Y1375000D02*
Y1368000D01*
G01X814300Y1375000D02*
X820700D01*
G01X807300Y1336500D02*
X815100D01*
G01X814300D02*
X820700D01*
G01X935233Y1089292D02*
X935483Y1089417D01*
X935775Y1089500D01*
X936108D01*
X936483Y1089375D01*
X936775Y1089167D01*
X936983Y1088917D01*
X937150Y1088500D01*
X937192Y1088125D01*
X937108Y1087750D01*
X936983Y1087500D01*
X936733Y1087250D01*
X936442Y1087083D01*
X936150Y1087000D01*
X935858D01*
X935567Y1087083D01*
X935317Y1087208D01*
X935108Y1087375D01*
G01X933133Y1087000D02*
X933050Y1087542D01*
X932925Y1088000D01*
X932758Y1088417D01*
X932550Y1088875D01*
X932217Y1089500D01*
X933883D01*
G01X929950D02*
X930283Y1089417D01*
X930533Y1089208D01*
X930700Y1088958D01*
X930825Y1088625D01*
X930867Y1088250D01*
X930825Y1087875D01*
X930700Y1087542D01*
X930533Y1087292D01*
X930283Y1087083D01*
X929950Y1087000D01*
X929617Y1087083D01*
X929367Y1087292D01*
X929200Y1087542D01*
X929075Y1087875D01*
X929033Y1088250D01*
X929075Y1088625D01*
X929200Y1088958D01*
X929367Y1089208D01*
X929617Y1089417D01*
X929950Y1089500D01*
G01X926850D02*
X927183Y1089417D01*
X927433Y1089208D01*
X927600Y1088958D01*
X927725Y1088625D01*
X927767Y1088250D01*
X927725Y1087875D01*
X927600Y1087542D01*
X927433Y1087292D01*
X927183Y1087083D01*
X926850Y1087000D01*
X926517Y1087083D01*
X926267Y1087292D01*
X926100Y1087542D01*
X925975Y1087875D01*
X925933Y1088250D01*
X925975Y1088625D01*
X926100Y1088958D01*
X926267Y1089208D01*
X926517Y1089417D01*
X926850Y1089500D01*
G01X934733Y1095292D02*
X934983Y1095417D01*
X935275Y1095500D01*
X935608D01*
X935983Y1095375D01*
X936275Y1095167D01*
X936483Y1094917D01*
X936650Y1094500D01*
X936692Y1094125D01*
X936608Y1093750D01*
X936483Y1093500D01*
X936233Y1093250D01*
X935942Y1093083D01*
X935650Y1093000D01*
X935358D01*
X935067Y1093083D01*
X934817Y1093208D01*
X934608Y1093375D01*
G01X932633Y1093000D02*
X932550Y1093542D01*
X932425Y1094000D01*
X932258Y1094417D01*
X932050Y1094875D01*
X931717Y1095500D01*
X933383D01*
G01X929450D02*
X929783Y1095417D01*
X930033Y1095208D01*
X930200Y1094958D01*
X930325Y1094625D01*
X930367Y1094250D01*
X930325Y1093875D01*
X930200Y1093542D01*
X930033Y1093292D01*
X929783Y1093083D01*
X929450Y1093000D01*
X929117Y1093083D01*
X928867Y1093292D01*
X928700Y1093542D01*
X928575Y1093875D01*
X928533Y1094250D01*
X928575Y1094625D01*
X928700Y1094958D01*
X928867Y1095208D01*
X929117Y1095417D01*
X929450Y1095500D01*
G01X926350Y1093000D02*
Y1095500D01*
X926850Y1095000D01*
G01Y1093000D02*
X925850D01*
G01X934733Y1102792D02*
X934983Y1102917D01*
X935275Y1103000D01*
X935608D01*
X935983Y1102875D01*
X936275Y1102667D01*
X936483Y1102417D01*
X936650Y1102000D01*
X936692Y1101625D01*
X936608Y1101250D01*
X936483Y1101000D01*
X936233Y1100750D01*
X935942Y1100583D01*
X935650Y1100500D01*
X935358D01*
X935067Y1100583D01*
X934817Y1100708D01*
X934608Y1100875D01*
G01X932633Y1100500D02*
X932550Y1101042D01*
X932425Y1101500D01*
X932258Y1101917D01*
X932050Y1102375D01*
X931717Y1103000D01*
X933383D01*
G01X929450D02*
X929783Y1102917D01*
X930033Y1102708D01*
X930200Y1102458D01*
X930325Y1102125D01*
X930367Y1101750D01*
X930325Y1101375D01*
X930200Y1101042D01*
X930033Y1100792D01*
X929783Y1100583D01*
X929450Y1100500D01*
X929117Y1100583D01*
X928867Y1100792D01*
X928700Y1101042D01*
X928575Y1101375D01*
X928533Y1101750D01*
X928575Y1102125D01*
X928700Y1102458D01*
X928867Y1102708D01*
X929117Y1102917D01*
X929450Y1103000D01*
G01X927142Y1102583D02*
X926892Y1102833D01*
X926600Y1102958D01*
X926267Y1103000D01*
X925850Y1102917D01*
X925558Y1102708D01*
X925475Y1102458D01*
X925517Y1102208D01*
X925683Y1102000D01*
X926517Y1101583D01*
X926892Y1101292D01*
X927142Y1100875D01*
X927225Y1100500D01*
X925475D01*
G01X934733Y1110292D02*
X934983Y1110417D01*
X935275Y1110500D01*
X935608D01*
X935983Y1110375D01*
X936275Y1110167D01*
X936483Y1109917D01*
X936650Y1109500D01*
X936692Y1109125D01*
X936608Y1108750D01*
X936483Y1108500D01*
X936233Y1108250D01*
X935942Y1108083D01*
X935650Y1108000D01*
X935358D01*
X935067Y1108083D01*
X934817Y1108208D01*
X934608Y1108375D01*
G01X932633Y1108000D02*
X932550Y1108542D01*
X932425Y1109000D01*
X932258Y1109417D01*
X932050Y1109875D01*
X931717Y1110500D01*
X933383D01*
G01X929450D02*
X929783Y1110417D01*
X930033Y1110208D01*
X930200Y1109958D01*
X930325Y1109625D01*
X930367Y1109250D01*
X930325Y1108875D01*
X930200Y1108542D01*
X930033Y1108292D01*
X929783Y1108083D01*
X929450Y1108000D01*
X929117Y1108083D01*
X928867Y1108292D01*
X928700Y1108542D01*
X928575Y1108875D01*
X928533Y1109250D01*
X928575Y1109625D01*
X928700Y1109958D01*
X928867Y1110208D01*
X929117Y1110417D01*
X929450Y1110500D01*
G01X927267Y1108500D02*
X927017Y1108208D01*
X926683Y1108042D01*
X926308Y1108000D01*
X925975Y1108042D01*
X925642Y1108250D01*
X925433Y1108500D01*
X925392Y1108750D01*
X925475Y1109042D01*
X925767Y1109250D01*
X926058Y1109333D01*
X926433D01*
G01X926058D02*
X925808Y1109458D01*
X925600Y1109667D01*
X925517Y1109917D01*
X925600Y1110167D01*
X925808Y1110375D01*
X926183Y1110500D01*
X926558Y1110458D01*
X926933Y1110292D01*
G01X945292Y1139267D02*
X945417Y1139017D01*
X945500Y1138725D01*
Y1138392D01*
X945375Y1138017D01*
X945167Y1137725D01*
X944917Y1137517D01*
X944500Y1137350D01*
X944125Y1137308D01*
X943750Y1137392D01*
X943500Y1137517D01*
X943250Y1137767D01*
X943083Y1138058D01*
X943000Y1138350D01*
Y1138642D01*
X943083Y1138933D01*
X943208Y1139183D01*
X943375Y1139392D01*
G01X943000Y1141367D02*
X943542Y1141450D01*
X944000Y1141575D01*
X944417Y1141742D01*
X944875Y1141950D01*
X945500Y1142283D01*
Y1140617D01*
G01Y1144550D02*
X945417Y1144217D01*
X945208Y1143967D01*
X944958Y1143800D01*
X944625Y1143675D01*
X944250Y1143633D01*
X943875Y1143675D01*
X943542Y1143800D01*
X943292Y1143967D01*
X943083Y1144217D01*
X943000Y1144550D01*
X943083Y1144883D01*
X943292Y1145133D01*
X943542Y1145300D01*
X943875Y1145425D01*
X944250Y1145467D01*
X944625Y1145425D01*
X944958Y1145300D01*
X945208Y1145133D01*
X945417Y1144883D01*
X945500Y1144550D01*
G01X943000Y1148150D02*
X945500D01*
X943708Y1146608D01*
Y1148692D01*
G01X950292Y1139267D02*
X950417Y1139017D01*
X950500Y1138725D01*
Y1138392D01*
X950375Y1138017D01*
X950167Y1137725D01*
X949917Y1137517D01*
X949500Y1137350D01*
X949125Y1137308D01*
X948750Y1137392D01*
X948500Y1137517D01*
X948250Y1137767D01*
X948083Y1138058D01*
X948000Y1138350D01*
Y1138642D01*
X948083Y1138933D01*
X948208Y1139183D01*
X948375Y1139392D01*
G01X948000Y1141367D02*
X948542Y1141450D01*
X949000Y1141575D01*
X949417Y1141742D01*
X949875Y1141950D01*
X950500Y1142283D01*
Y1140617D01*
G01Y1144550D02*
X950417Y1144217D01*
X950208Y1143967D01*
X949958Y1143800D01*
X949625Y1143675D01*
X949250Y1143633D01*
X948875Y1143675D01*
X948542Y1143800D01*
X948292Y1143967D01*
X948083Y1144217D01*
X948000Y1144550D01*
X948083Y1144883D01*
X948292Y1145133D01*
X948542Y1145300D01*
X948875Y1145425D01*
X949250Y1145467D01*
X949625Y1145425D01*
X949958Y1145300D01*
X950208Y1145133D01*
X950417Y1144883D01*
X950500Y1144550D01*
G01X948375Y1146733D02*
X948167Y1146983D01*
X948042Y1147275D01*
X948000Y1147650D01*
X948083Y1148025D01*
X948250Y1148317D01*
X948542Y1148525D01*
X948875Y1148567D01*
X949208Y1148483D01*
X949417Y1148275D01*
X949583Y1147983D01*
X949625Y1147692D01*
X949583Y1147400D01*
X949417Y1147025D01*
X950500Y1147150D01*
Y1148275D01*
G01X955292Y1139267D02*
X955417Y1139017D01*
X955500Y1138725D01*
Y1138392D01*
X955375Y1138017D01*
X955167Y1137725D01*
X954917Y1137517D01*
X954500Y1137350D01*
X954125Y1137308D01*
X953750Y1137392D01*
X953500Y1137517D01*
X953250Y1137767D01*
X953083Y1138058D01*
X953000Y1138350D01*
Y1138642D01*
X953083Y1138933D01*
X953208Y1139183D01*
X953375Y1139392D01*
G01X953000Y1141367D02*
X953542Y1141450D01*
X954000Y1141575D01*
X954417Y1141742D01*
X954875Y1141950D01*
X955500Y1142283D01*
Y1140617D01*
G01Y1144550D02*
X955417Y1144217D01*
X955208Y1143967D01*
X954958Y1143800D01*
X954625Y1143675D01*
X954250Y1143633D01*
X953875Y1143675D01*
X953542Y1143800D01*
X953292Y1143967D01*
X953083Y1144217D01*
X953000Y1144550D01*
X953083Y1144883D01*
X953292Y1145133D01*
X953542Y1145300D01*
X953875Y1145425D01*
X954250Y1145467D01*
X954625Y1145425D01*
X954958Y1145300D01*
X955208Y1145133D01*
X955417Y1144883D01*
X955500Y1144550D01*
G01X954042Y1146858D02*
X954333Y1147150D01*
X954500Y1147400D01*
X954583Y1147733D01*
X954500Y1148025D01*
X954333Y1148233D01*
X954083Y1148400D01*
X953792Y1148442D01*
X953542Y1148400D01*
X953292Y1148233D01*
X953083Y1147983D01*
X953000Y1147692D01*
X953083Y1147358D01*
X953333Y1147067D01*
X953708Y1146900D01*
X954125Y1146858D01*
X954667Y1146942D01*
X954958Y1147067D01*
X955250Y1147275D01*
X955458Y1147567D01*
X955500Y1147858D01*
X955417Y1148150D01*
X955208Y1148358D01*
G01X958750Y1138650D02*
Y1139483D01*
X958000D01*
X957750Y1139233D01*
X957583Y1138942D01*
X957500Y1138525D01*
X957583Y1138108D01*
X957750Y1137817D01*
X958000Y1137567D01*
X958292Y1137400D01*
X958625Y1137317D01*
X958917D01*
X959167Y1137400D01*
X959458Y1137567D01*
X959708Y1137817D01*
X959875Y1138067D01*
X960000Y1138400D01*
Y1138692D01*
X959917Y1139025D01*
X959750Y1139275D01*
G01X957500Y1141500D02*
X960000D01*
X959500Y1141000D01*
G01X957500D02*
Y1142000D01*
G01X960000Y1144600D02*
X959917Y1144267D01*
X959708Y1144017D01*
X959458Y1143850D01*
X959125Y1143725D01*
X958750Y1143683D01*
X958375Y1143725D01*
X958042Y1143850D01*
X957792Y1144017D01*
X957583Y1144267D01*
X957500Y1144600D01*
X957583Y1144933D01*
X957792Y1145183D01*
X958042Y1145350D01*
X958375Y1145475D01*
X958750Y1145517D01*
X959125Y1145475D01*
X959458Y1145350D01*
X959708Y1145183D01*
X959917Y1144933D01*
X960000Y1144600D01*
G01X955891Y1087699D02*
X991291D01*
Y1115699D01*
X955891D01*
Y1087699D01*
G01X970583Y1074000D02*
Y1076500D01*
X969542D01*
X969208Y1076375D01*
X969000Y1076208D01*
X968917Y1075875D01*
X969000Y1075542D01*
X969250Y1075333D01*
X969542Y1075208D01*
X970583D01*
G01X969542D02*
X968917Y1074000D01*
G01X966650D02*
Y1076500D01*
X967150Y1076000D01*
G01Y1074000D02*
X966150D01*
G01X963550D02*
Y1076500D01*
X964050Y1076000D01*
G01Y1074000D02*
X963050D01*
G01X960450D02*
X960158Y1074042D01*
X959825Y1074167D01*
X959617Y1074375D01*
X959533Y1074667D01*
X959617Y1074958D01*
X959867Y1075208D01*
X960242Y1075333D01*
X960658D01*
X960908Y1075417D01*
X961117Y1075625D01*
X961200Y1075917D01*
X961075Y1076208D01*
X960783Y1076417D01*
X960450Y1076500D01*
X960117Y1076417D01*
X959825Y1076208D01*
X959700Y1075917D01*
X959783Y1075625D01*
X959992Y1075417D01*
X960242Y1075333D01*
X960658D01*
X961033Y1075208D01*
X961283Y1074958D01*
X961367Y1074667D01*
X961283Y1074375D01*
X961075Y1074167D01*
X960742Y1074042D01*
X960450Y1074000D01*
G01X958142Y1076083D02*
X957892Y1076333D01*
X957600Y1076458D01*
X957267Y1076500D01*
X956850Y1076417D01*
X956558Y1076208D01*
X956475Y1075958D01*
X956517Y1075708D01*
X956683Y1075500D01*
X957517Y1075083D01*
X957892Y1074792D01*
X958142Y1074375D01*
X958225Y1074000D01*
X956475D01*
G01X957300Y1086000D02*
X966000D01*
G01X957300Y1079000D02*
Y1086000D01*
G01X963700Y1079000D02*
X957300D01*
G01X872867Y1309726D02*
X872992Y1309476D01*
X873075Y1309184D01*
Y1308851D01*
X872950Y1308476D01*
X872742Y1308184D01*
X872492Y1307976D01*
X872075Y1307809D01*
X871700Y1307767D01*
X871325Y1307851D01*
X871075Y1307976D01*
X870825Y1308226D01*
X870658Y1308517D01*
X870575Y1308809D01*
Y1309101D01*
X870658Y1309392D01*
X870783Y1309642D01*
X870950Y1309851D01*
G01Y1310992D02*
X870742Y1311242D01*
X870617Y1311534D01*
X870575Y1311909D01*
X870658Y1312284D01*
X870825Y1312576D01*
X871117Y1312784D01*
X871450Y1312826D01*
X871783Y1312742D01*
X871992Y1312534D01*
X872158Y1312242D01*
X872200Y1311951D01*
X872158Y1311659D01*
X871992Y1311284D01*
X873075Y1311409D01*
Y1312534D01*
G01X871617Y1314217D02*
X871908Y1314509D01*
X872075Y1314759D01*
X872158Y1315092D01*
X872075Y1315384D01*
X871908Y1315592D01*
X871658Y1315759D01*
X871367Y1315801D01*
X871117Y1315759D01*
X870867Y1315592D01*
X870658Y1315342D01*
X870575Y1315051D01*
X870658Y1314717D01*
X870908Y1314426D01*
X871283Y1314259D01*
X871700Y1314217D01*
X872242Y1314301D01*
X872533Y1314426D01*
X872825Y1314634D01*
X873033Y1314926D01*
X873075Y1315217D01*
X872992Y1315509D01*
X872783Y1315717D01*
G01X870575Y1318026D02*
X871117Y1318109D01*
X871575Y1318234D01*
X871992Y1318401D01*
X872450Y1318609D01*
X873075Y1318942D01*
Y1317276D01*
G01X876739Y1286150D02*
Y1304850D01*
X866439D01*
Y1286150D01*
X876739D01*
G01X884443Y1308792D02*
X884568Y1308542D01*
X884651Y1308250D01*
Y1307917D01*
X884526Y1307542D01*
X884318Y1307250D01*
X884068Y1307042D01*
X883651Y1306875D01*
X883276Y1306833D01*
X882901Y1306917D01*
X882651Y1307042D01*
X882401Y1307292D01*
X882234Y1307583D01*
X882151Y1307875D01*
Y1308167D01*
X882234Y1308458D01*
X882359Y1308708D01*
X882526Y1308917D01*
G01Y1310058D02*
X882318Y1310308D01*
X882193Y1310600D01*
X882151Y1310975D01*
X882234Y1311350D01*
X882401Y1311642D01*
X882693Y1311850D01*
X883026Y1311892D01*
X883359Y1311808D01*
X883568Y1311600D01*
X883734Y1311308D01*
X883776Y1311017D01*
X883734Y1310725D01*
X883568Y1310350D01*
X884651Y1310475D01*
Y1311600D01*
G01X882151Y1314075D02*
X884651D01*
X884151Y1313575D01*
G01X882151D02*
Y1314575D01*
G01X884234Y1316383D02*
X884484Y1316633D01*
X884609Y1316925D01*
X884651Y1317258D01*
X884568Y1317675D01*
X884359Y1317967D01*
X884109Y1318050D01*
X883859Y1318008D01*
X883651Y1317842D01*
X883234Y1317008D01*
X882943Y1316633D01*
X882526Y1316383D01*
X882151Y1316300D01*
Y1318050D01*
G01X889210Y1286182D02*
Y1304882D01*
X878910D01*
Y1286182D01*
X889210D01*
G01X877814Y1415788D02*
X877939Y1415538D01*
X878022Y1415246D01*
Y1414913D01*
X877897Y1414538D01*
X877689Y1414246D01*
X877439Y1414038D01*
X877022Y1413871D01*
X876647Y1413829D01*
X876272Y1413913D01*
X876022Y1414038D01*
X875772Y1414288D01*
X875605Y1414579D01*
X875522Y1414871D01*
Y1415163D01*
X875605Y1415454D01*
X875730Y1415704D01*
X875897Y1415913D01*
G01Y1417054D02*
X875689Y1417304D01*
X875564Y1417596D01*
X875522Y1417971D01*
X875605Y1418346D01*
X875772Y1418638D01*
X876064Y1418846D01*
X876397Y1418888D01*
X876730Y1418804D01*
X876939Y1418596D01*
X877105Y1418304D01*
X877147Y1418013D01*
X877105Y1417721D01*
X876939Y1417346D01*
X878022Y1417471D01*
Y1418596D01*
G01X875522Y1421071D02*
X878022D01*
X877522Y1420571D01*
G01X875522D02*
Y1421571D01*
G01X876564Y1423379D02*
X876855Y1423671D01*
X877022Y1423921D01*
X877105Y1424254D01*
X877022Y1424546D01*
X876855Y1424754D01*
X876605Y1424921D01*
X876314Y1424963D01*
X876064Y1424921D01*
X875814Y1424754D01*
X875605Y1424504D01*
X875522Y1424213D01*
X875605Y1423879D01*
X875855Y1423588D01*
X876230Y1423421D01*
X876647Y1423379D01*
X877189Y1423463D01*
X877480Y1423588D01*
X877772Y1423796D01*
X877980Y1424088D01*
X878022Y1424379D01*
X877939Y1424671D01*
X877730Y1424879D01*
G01X871350Y1408850D02*
Y1390150D01*
X881650D01*
Y1408850D01*
X871350D01*
G01X1018792Y1124767D02*
X1018917Y1124517D01*
X1019000Y1124225D01*
Y1123892D01*
X1018875Y1123517D01*
X1018667Y1123225D01*
X1018417Y1123017D01*
X1018000Y1122850D01*
X1017625Y1122808D01*
X1017250Y1122892D01*
X1017000Y1123017D01*
X1016750Y1123267D01*
X1016583Y1123558D01*
X1016500Y1123850D01*
Y1124142D01*
X1016583Y1124433D01*
X1016708Y1124683D01*
X1016875Y1124892D01*
G01X1017542Y1126158D02*
X1017833Y1126450D01*
X1018000Y1126700D01*
X1018083Y1127033D01*
X1018000Y1127325D01*
X1017833Y1127533D01*
X1017583Y1127700D01*
X1017292Y1127742D01*
X1017042Y1127700D01*
X1016792Y1127533D01*
X1016583Y1127283D01*
X1016500Y1126992D01*
X1016583Y1126658D01*
X1016833Y1126367D01*
X1017208Y1126200D01*
X1017625Y1126158D01*
X1018167Y1126242D01*
X1018458Y1126367D01*
X1018750Y1126575D01*
X1018958Y1126867D01*
X1019000Y1127158D01*
X1018917Y1127450D01*
X1018708Y1127658D01*
G01X1016792Y1129342D02*
X1016583Y1129633D01*
X1016500Y1129967D01*
X1016583Y1130300D01*
X1016833Y1130592D01*
X1017208Y1130800D01*
X1017583Y1130883D01*
X1018042D01*
X1018417Y1130800D01*
X1018750Y1130592D01*
X1018917Y1130342D01*
X1019000Y1130050D01*
X1018917Y1129717D01*
X1018750Y1129467D01*
X1018500Y1129300D01*
X1018167Y1129217D01*
X1017875Y1129300D01*
X1017583Y1129508D01*
X1017417Y1129758D01*
X1017375Y1130050D01*
X1017458Y1130383D01*
X1017667Y1130633D01*
X1018042Y1130883D01*
G01X1018583Y1132358D02*
X1018833Y1132608D01*
X1018958Y1132900D01*
X1019000Y1133233D01*
X1018917Y1133650D01*
X1018708Y1133942D01*
X1018458Y1134025D01*
X1018208Y1133983D01*
X1018000Y1133817D01*
X1017583Y1132983D01*
X1017292Y1132608D01*
X1016875Y1132358D01*
X1016500Y1132275D01*
Y1134025D01*
G01X1019292Y1090767D02*
X1019417Y1090517D01*
X1019500Y1090225D01*
Y1089892D01*
X1019375Y1089517D01*
X1019167Y1089225D01*
X1018917Y1089017D01*
X1018500Y1088850D01*
X1018125Y1088808D01*
X1017750Y1088892D01*
X1017500Y1089017D01*
X1017250Y1089267D01*
X1017083Y1089558D01*
X1017000Y1089850D01*
Y1090142D01*
X1017083Y1090433D01*
X1017208Y1090683D01*
X1017375Y1090892D01*
G01X1018042Y1092158D02*
X1018333Y1092450D01*
X1018500Y1092700D01*
X1018583Y1093033D01*
X1018500Y1093325D01*
X1018333Y1093533D01*
X1018083Y1093700D01*
X1017792Y1093742D01*
X1017542Y1093700D01*
X1017292Y1093533D01*
X1017083Y1093283D01*
X1017000Y1092992D01*
X1017083Y1092658D01*
X1017333Y1092367D01*
X1017708Y1092200D01*
X1018125Y1092158D01*
X1018667Y1092242D01*
X1018958Y1092367D01*
X1019250Y1092575D01*
X1019458Y1092867D01*
X1019500Y1093158D01*
X1019417Y1093450D01*
X1019208Y1093658D01*
G01X1017292Y1095342D02*
X1017083Y1095633D01*
X1017000Y1095967D01*
X1017083Y1096300D01*
X1017333Y1096592D01*
X1017708Y1096800D01*
X1018083Y1096883D01*
X1018542D01*
X1018917Y1096800D01*
X1019250Y1096592D01*
X1019417Y1096342D01*
X1019500Y1096050D01*
X1019417Y1095717D01*
X1019250Y1095467D01*
X1019000Y1095300D01*
X1018667Y1095217D01*
X1018375Y1095300D01*
X1018083Y1095508D01*
X1017917Y1095758D01*
X1017875Y1096050D01*
X1017958Y1096383D01*
X1018167Y1096633D01*
X1018542Y1096883D01*
G01X1017375Y1098233D02*
X1017167Y1098483D01*
X1017042Y1098775D01*
X1017000Y1099150D01*
X1017083Y1099525D01*
X1017250Y1099817D01*
X1017542Y1100025D01*
X1017875Y1100067D01*
X1018208Y1099983D01*
X1018417Y1099775D01*
X1018583Y1099483D01*
X1018625Y1099192D01*
X1018583Y1098900D01*
X1018417Y1098525D01*
X1019500Y1098650D01*
Y1099775D01*
G01X1047733Y1124292D02*
X1047983Y1124417D01*
X1048275Y1124500D01*
X1048608D01*
X1048983Y1124375D01*
X1049275Y1124167D01*
X1049483Y1123917D01*
X1049650Y1123500D01*
X1049692Y1123125D01*
X1049608Y1122750D01*
X1049483Y1122500D01*
X1049233Y1122250D01*
X1048942Y1122083D01*
X1048650Y1122000D01*
X1048358D01*
X1048067Y1122083D01*
X1047817Y1122208D01*
X1047608Y1122375D01*
G01X1046342Y1123042D02*
X1046050Y1123333D01*
X1045800Y1123500D01*
X1045467Y1123583D01*
X1045175Y1123500D01*
X1044967Y1123333D01*
X1044800Y1123083D01*
X1044758Y1122792D01*
X1044800Y1122542D01*
X1044967Y1122292D01*
X1045217Y1122083D01*
X1045508Y1122000D01*
X1045842Y1122083D01*
X1046133Y1122333D01*
X1046300Y1122708D01*
X1046342Y1123125D01*
X1046258Y1123667D01*
X1046133Y1123958D01*
X1045925Y1124250D01*
X1045633Y1124458D01*
X1045342Y1124500D01*
X1045050Y1124417D01*
X1044842Y1124208D01*
G01X1043158Y1122292D02*
X1042867Y1122083D01*
X1042533Y1122000D01*
X1042200Y1122083D01*
X1041908Y1122333D01*
X1041700Y1122708D01*
X1041617Y1123083D01*
Y1123542D01*
X1041700Y1123917D01*
X1041908Y1124250D01*
X1042158Y1124417D01*
X1042450Y1124500D01*
X1042783Y1124417D01*
X1043033Y1124250D01*
X1043200Y1124000D01*
X1043283Y1123667D01*
X1043200Y1123375D01*
X1042992Y1123083D01*
X1042742Y1122917D01*
X1042450Y1122875D01*
X1042117Y1122958D01*
X1041867Y1123167D01*
X1041617Y1123542D01*
G01X1040058Y1122292D02*
X1039767Y1122083D01*
X1039433Y1122000D01*
X1039100Y1122083D01*
X1038808Y1122333D01*
X1038600Y1122708D01*
X1038517Y1123083D01*
Y1123542D01*
X1038600Y1123917D01*
X1038808Y1124250D01*
X1039058Y1124417D01*
X1039350Y1124500D01*
X1039683Y1124417D01*
X1039933Y1124250D01*
X1040100Y1124000D01*
X1040183Y1123667D01*
X1040100Y1123375D01*
X1039892Y1123083D01*
X1039642Y1122917D01*
X1039350Y1122875D01*
X1039017Y1122958D01*
X1038767Y1123167D01*
X1038517Y1123542D01*
G01X982733Y1076292D02*
X982983Y1076417D01*
X983275Y1076500D01*
X983608D01*
X983983Y1076375D01*
X984275Y1076167D01*
X984483Y1075917D01*
X984650Y1075500D01*
X984692Y1075125D01*
X984608Y1074750D01*
X984483Y1074500D01*
X984233Y1074250D01*
X983942Y1074083D01*
X983650Y1074000D01*
X983358D01*
X983067Y1074083D01*
X982817Y1074208D01*
X982608Y1074375D01*
G01X981342Y1075042D02*
X981050Y1075333D01*
X980800Y1075500D01*
X980467Y1075583D01*
X980175Y1075500D01*
X979967Y1075333D01*
X979800Y1075083D01*
X979758Y1074792D01*
X979800Y1074542D01*
X979967Y1074292D01*
X980217Y1074083D01*
X980508Y1074000D01*
X980842Y1074083D01*
X981133Y1074333D01*
X981300Y1074708D01*
X981342Y1075125D01*
X981258Y1075667D01*
X981133Y1075958D01*
X980925Y1076250D01*
X980633Y1076458D01*
X980342Y1076500D01*
X980050Y1076417D01*
X979842Y1076208D01*
G01X978158Y1074292D02*
X977867Y1074083D01*
X977533Y1074000D01*
X977200Y1074083D01*
X976908Y1074333D01*
X976700Y1074708D01*
X976617Y1075083D01*
Y1075542D01*
X976700Y1075917D01*
X976908Y1076250D01*
X977158Y1076417D01*
X977450Y1076500D01*
X977783Y1076417D01*
X978033Y1076250D01*
X978200Y1076000D01*
X978283Y1075667D01*
X978200Y1075375D01*
X977992Y1075083D01*
X977742Y1074917D01*
X977450Y1074875D01*
X977117Y1074958D01*
X976867Y1075167D01*
X976617Y1075542D01*
G01X974433Y1074000D02*
X974350Y1074542D01*
X974225Y1075000D01*
X974058Y1075417D01*
X973850Y1075875D01*
X973517Y1076500D01*
X975183D01*
G01X1010533Y1083000D02*
Y1085500D01*
X1009492D01*
X1009158Y1085375D01*
X1008950Y1085208D01*
X1008867Y1084875D01*
X1008950Y1084542D01*
X1009200Y1084333D01*
X1009492Y1084208D01*
X1010533D01*
G01X1009492D02*
X1008867Y1083000D01*
G01X1006600D02*
Y1085500D01*
X1007100Y1085000D01*
G01Y1083000D02*
X1006100D01*
G01X1003500D02*
Y1085500D01*
X1004000Y1085000D01*
G01Y1083000D02*
X1003000D01*
G01X1000400D02*
X1000108Y1083042D01*
X999775Y1083167D01*
X999567Y1083375D01*
X999483Y1083667D01*
X999567Y1083958D01*
X999817Y1084208D01*
X1000192Y1084333D01*
X1000608D01*
X1000858Y1084417D01*
X1001067Y1084625D01*
X1001150Y1084917D01*
X1001025Y1085208D01*
X1000733Y1085417D01*
X1000400Y1085500D01*
X1000067Y1085417D01*
X999775Y1085208D01*
X999650Y1084917D01*
X999733Y1084625D01*
X999942Y1084417D01*
X1000192Y1084333D01*
X1000608D01*
X1000983Y1084208D01*
X1001233Y1083958D01*
X1001317Y1083667D01*
X1001233Y1083375D01*
X1001025Y1083167D01*
X1000692Y1083042D01*
X1000400Y1083000D01*
G01X996800D02*
Y1085500D01*
X998342Y1083708D01*
X996258D01*
G01X1003289Y1090328D02*
Y1094328D01*
X1010689D01*
G01X1049533Y1117500D02*
Y1120000D01*
X1048492D01*
X1048158Y1119875D01*
X1047950Y1119708D01*
X1047867Y1119375D01*
X1047950Y1119042D01*
X1048200Y1118833D01*
X1048492Y1118708D01*
X1049533D01*
G01X1048492D02*
X1047867Y1117500D01*
G01X1045600D02*
Y1120000D01*
X1046100Y1119500D01*
G01Y1117500D02*
X1045100D01*
G01X1042500D02*
Y1120000D01*
X1043000Y1119500D01*
G01Y1117500D02*
X1042000D01*
G01X1039483D02*
X1039400Y1118042D01*
X1039275Y1118500D01*
X1039108Y1118917D01*
X1038900Y1119375D01*
X1038567Y1120000D01*
X1040233D01*
G01X1037217Y1117875D02*
X1036967Y1117667D01*
X1036675Y1117542D01*
X1036300Y1117500D01*
X1035925Y1117583D01*
X1035633Y1117750D01*
X1035425Y1118042D01*
X1035383Y1118375D01*
X1035467Y1118708D01*
X1035675Y1118917D01*
X1035967Y1119083D01*
X1036258Y1119125D01*
X1036550Y1119083D01*
X1036925Y1118917D01*
X1036800Y1120000D01*
X1035675D01*
G01X1026793Y1120601D02*
Y1116601D01*
X1019393D01*
G01X1032000Y1126967D02*
X1034500D01*
Y1128008D01*
X1034375Y1128342D01*
X1034208Y1128550D01*
X1033875Y1128633D01*
X1033542Y1128550D01*
X1033333Y1128300D01*
X1033208Y1128008D01*
Y1126967D01*
G01Y1128008D02*
X1032000Y1128633D01*
G01Y1130900D02*
X1034500D01*
X1034000Y1130400D01*
G01X1032000D02*
Y1131400D01*
G01Y1134000D02*
X1034500D01*
X1034000Y1133500D01*
G01X1032000D02*
Y1134500D01*
G01Y1137017D02*
X1032542Y1137100D01*
X1033000Y1137225D01*
X1033417Y1137392D01*
X1033875Y1137600D01*
X1034500Y1137933D01*
Y1136267D01*
G01X1032000Y1140117D02*
X1032542Y1140200D01*
X1033000Y1140325D01*
X1033417Y1140492D01*
X1033875Y1140700D01*
X1034500Y1141033D01*
Y1139367D01*
G01X1024700Y1135600D02*
X1028700D01*
Y1128200D01*
G01X1049533Y1109500D02*
Y1112000D01*
X1048492D01*
X1048158Y1111875D01*
X1047950Y1111708D01*
X1047867Y1111375D01*
X1047950Y1111042D01*
X1048200Y1110833D01*
X1048492Y1110708D01*
X1049533D01*
G01X1048492D02*
X1047867Y1109500D01*
G01X1045600D02*
Y1112000D01*
X1046100Y1111500D01*
G01Y1109500D02*
X1045100D01*
G01X1042500D02*
Y1112000D01*
X1043000Y1111500D01*
G01Y1109500D02*
X1042000D01*
G01X1039400D02*
X1039108Y1109542D01*
X1038775Y1109667D01*
X1038567Y1109875D01*
X1038483Y1110167D01*
X1038567Y1110458D01*
X1038817Y1110708D01*
X1039192Y1110833D01*
X1039608D01*
X1039858Y1110917D01*
X1040067Y1111125D01*
X1040150Y1111417D01*
X1040025Y1111708D01*
X1039733Y1111917D01*
X1039400Y1112000D01*
X1039067Y1111917D01*
X1038775Y1111708D01*
X1038650Y1111417D01*
X1038733Y1111125D01*
X1038942Y1110917D01*
X1039192Y1110833D01*
X1039608D01*
X1039983Y1110708D01*
X1040233Y1110458D01*
X1040317Y1110167D01*
X1040233Y1109875D01*
X1040025Y1109667D01*
X1039692Y1109542D01*
X1039400Y1109500D01*
G01X1036300Y1112000D02*
X1036633Y1111917D01*
X1036883Y1111708D01*
X1037050Y1111458D01*
X1037175Y1111125D01*
X1037217Y1110750D01*
X1037175Y1110375D01*
X1037050Y1110042D01*
X1036883Y1109792D01*
X1036633Y1109583D01*
X1036300Y1109500D01*
X1035967Y1109583D01*
X1035717Y1109792D01*
X1035550Y1110042D01*
X1035425Y1110375D01*
X1035383Y1110750D01*
X1035425Y1111125D01*
X1035550Y1111458D01*
X1035717Y1111708D01*
X1035967Y1111917D01*
X1036300Y1112000D01*
G01X1022287Y1107799D02*
Y1111799D01*
X1029687D01*
G01X1012500Y1072967D02*
X1015000D01*
Y1074008D01*
X1014875Y1074342D01*
X1014708Y1074550D01*
X1014375Y1074633D01*
X1014042Y1074550D01*
X1013833Y1074300D01*
X1013708Y1074008D01*
Y1072967D01*
G01Y1074008D02*
X1012500Y1074633D01*
G01Y1076900D02*
X1015000D01*
X1014500Y1076400D01*
G01X1012500D02*
Y1077400D01*
G01Y1080000D02*
X1015000D01*
X1014500Y1079500D01*
G01X1012500D02*
Y1080500D01*
G01Y1083100D02*
X1012542Y1083392D01*
X1012667Y1083725D01*
X1012875Y1083933D01*
X1013167Y1084017D01*
X1013458Y1083933D01*
X1013708Y1083683D01*
X1013833Y1083308D01*
Y1082892D01*
X1013917Y1082642D01*
X1014125Y1082433D01*
X1014417Y1082350D01*
X1014708Y1082475D01*
X1014917Y1082767D01*
X1015000Y1083100D01*
X1014917Y1083433D01*
X1014708Y1083725D01*
X1014417Y1083850D01*
X1014125Y1083767D01*
X1013917Y1083558D01*
X1013833Y1083308D01*
Y1082892D01*
X1013708Y1082517D01*
X1013458Y1082267D01*
X1013167Y1082183D01*
X1012875Y1082267D01*
X1012667Y1082475D01*
X1012542Y1082808D01*
X1012500Y1083100D01*
G01X1013000Y1085283D02*
X1012708Y1085533D01*
X1012542Y1085867D01*
X1012500Y1086242D01*
X1012542Y1086575D01*
X1012750Y1086908D01*
X1013000Y1087117D01*
X1013250Y1087158D01*
X1013542Y1087075D01*
X1013750Y1086783D01*
X1013833Y1086492D01*
Y1086117D01*
G01Y1086492D02*
X1013958Y1086742D01*
X1014167Y1086950D01*
X1014417Y1087033D01*
X1014667Y1086950D01*
X1014875Y1086742D01*
X1015000Y1086367D01*
X1014958Y1085992D01*
X1014792Y1085617D01*
G01X1011231Y1100071D02*
X1015231D01*
Y1092671D01*
G01X983378Y1117269D02*
Y1119769D01*
X982337D01*
X982003Y1119644D01*
X981795Y1119477D01*
X981712Y1119144D01*
X981795Y1118811D01*
X982045Y1118602D01*
X982337Y1118477D01*
X983378D01*
G01X982337D02*
X981712Y1117269D01*
G01X979445D02*
Y1119769D01*
X979945Y1119269D01*
G01Y1117269D02*
X978945D01*
G01X976345D02*
Y1119769D01*
X976845Y1119269D01*
G01Y1117269D02*
X975845D01*
G01X973328D02*
X973245Y1117811D01*
X973120Y1118269D01*
X972953Y1118686D01*
X972745Y1119144D01*
X972412Y1119769D01*
X974078D01*
G01X970853Y1117561D02*
X970562Y1117352D01*
X970228Y1117269D01*
X969895Y1117352D01*
X969603Y1117602D01*
X969395Y1117977D01*
X969312Y1118352D01*
Y1118811D01*
X969395Y1119186D01*
X969603Y1119519D01*
X969853Y1119686D01*
X970145Y1119769D01*
X970478Y1119686D01*
X970728Y1119519D01*
X970895Y1119269D01*
X970978Y1118936D01*
X970895Y1118644D01*
X970687Y1118352D01*
X970437Y1118186D01*
X970145Y1118144D01*
X969812Y1118227D01*
X969562Y1118436D01*
X969312Y1118811D01*
G01X984500Y1124200D02*
X988500D01*
Y1116800D01*
G01X967000Y1137967D02*
X969500D01*
Y1139008D01*
X969375Y1139342D01*
X969208Y1139550D01*
X968875Y1139633D01*
X968542Y1139550D01*
X968333Y1139300D01*
X968208Y1139008D01*
Y1137967D01*
G01Y1139008D02*
X967000Y1139633D01*
G01Y1141900D02*
X969500D01*
X969000Y1141400D01*
G01X967000D02*
Y1142400D01*
G01Y1145000D02*
X969500D01*
X969000Y1144500D01*
G01X967000D02*
Y1145500D01*
G01Y1148100D02*
X967042Y1148392D01*
X967167Y1148725D01*
X967375Y1148933D01*
X967667Y1149017D01*
X967958Y1148933D01*
X968208Y1148683D01*
X968333Y1148308D01*
Y1147892D01*
X968417Y1147642D01*
X968625Y1147433D01*
X968917Y1147350D01*
X969208Y1147475D01*
X969417Y1147767D01*
X969500Y1148100D01*
X969417Y1148433D01*
X969208Y1148725D01*
X968917Y1148850D01*
X968625Y1148767D01*
X968417Y1148558D01*
X968333Y1148308D01*
Y1147892D01*
X968208Y1147517D01*
X967958Y1147267D01*
X967667Y1147183D01*
X967375Y1147267D01*
X967167Y1147475D01*
X967042Y1147808D01*
X967000Y1148100D01*
G01Y1151200D02*
X969500D01*
X969000Y1150700D01*
G01X967000D02*
Y1151700D01*
G01X976200Y1124600D02*
X972200D01*
Y1132000D01*
G01X1047733Y1115792D02*
X1047983Y1115917D01*
X1048275Y1116000D01*
X1048608D01*
X1048983Y1115875D01*
X1049275Y1115667D01*
X1049483Y1115417D01*
X1049650Y1115000D01*
X1049692Y1114625D01*
X1049608Y1114250D01*
X1049483Y1114000D01*
X1049233Y1113750D01*
X1048942Y1113583D01*
X1048650Y1113500D01*
X1048358D01*
X1048067Y1113583D01*
X1047817Y1113708D01*
X1047608Y1113875D01*
G01X1046342Y1114542D02*
X1046050Y1114833D01*
X1045800Y1115000D01*
X1045467Y1115083D01*
X1045175Y1115000D01*
X1044967Y1114833D01*
X1044800Y1114583D01*
X1044758Y1114292D01*
X1044800Y1114042D01*
X1044967Y1113792D01*
X1045217Y1113583D01*
X1045508Y1113500D01*
X1045842Y1113583D01*
X1046133Y1113833D01*
X1046300Y1114208D01*
X1046342Y1114625D01*
X1046258Y1115167D01*
X1046133Y1115458D01*
X1045925Y1115750D01*
X1045633Y1115958D01*
X1045342Y1116000D01*
X1045050Y1115917D01*
X1044842Y1115708D01*
G01X1043158Y1113792D02*
X1042867Y1113583D01*
X1042533Y1113500D01*
X1042200Y1113583D01*
X1041908Y1113833D01*
X1041700Y1114208D01*
X1041617Y1114583D01*
Y1115042D01*
X1041700Y1115417D01*
X1041908Y1115750D01*
X1042158Y1115917D01*
X1042450Y1116000D01*
X1042783Y1115917D01*
X1043033Y1115750D01*
X1043200Y1115500D01*
X1043283Y1115167D01*
X1043200Y1114875D01*
X1042992Y1114583D01*
X1042742Y1114417D01*
X1042450Y1114375D01*
X1042117Y1114458D01*
X1041867Y1114667D01*
X1041617Y1115042D01*
G01X1040142Y1114542D02*
X1039850Y1114833D01*
X1039600Y1115000D01*
X1039267Y1115083D01*
X1038975Y1115000D01*
X1038767Y1114833D01*
X1038600Y1114583D01*
X1038558Y1114292D01*
X1038600Y1114042D01*
X1038767Y1113792D01*
X1039017Y1113583D01*
X1039308Y1113500D01*
X1039642Y1113583D01*
X1039933Y1113833D01*
X1040100Y1114208D01*
X1040142Y1114625D01*
X1040058Y1115167D01*
X1039933Y1115458D01*
X1039725Y1115750D01*
X1039433Y1115958D01*
X1039142Y1116000D01*
X1038850Y1115917D01*
X1038642Y1115708D01*
G01X1002233Y1089292D02*
X1002483Y1089417D01*
X1002775Y1089500D01*
X1003108D01*
X1003483Y1089375D01*
X1003775Y1089167D01*
X1003983Y1088917D01*
X1004150Y1088500D01*
X1004192Y1088125D01*
X1004108Y1087750D01*
X1003983Y1087500D01*
X1003733Y1087250D01*
X1003442Y1087083D01*
X1003150Y1087000D01*
X1002858D01*
X1002567Y1087083D01*
X1002317Y1087208D01*
X1002108Y1087375D01*
G01X1000133Y1087000D02*
X1000050Y1087542D01*
X999925Y1088000D01*
X999758Y1088417D01*
X999550Y1088875D01*
X999217Y1089500D01*
X1000883D01*
G01X996950D02*
X997283Y1089417D01*
X997533Y1089208D01*
X997700Y1088958D01*
X997825Y1088625D01*
X997867Y1088250D01*
X997825Y1087875D01*
X997700Y1087542D01*
X997533Y1087292D01*
X997283Y1087083D01*
X996950Y1087000D01*
X996617Y1087083D01*
X996367Y1087292D01*
X996200Y1087542D01*
X996075Y1087875D01*
X996033Y1088250D01*
X996075Y1088625D01*
X996200Y1088958D01*
X996367Y1089208D01*
X996617Y1089417D01*
X996950Y1089500D01*
G01X993933Y1087000D02*
X993850Y1087542D01*
X993725Y1088000D01*
X993558Y1088417D01*
X993350Y1088875D01*
X993017Y1089500D01*
X994683D01*
G01X980733Y1140792D02*
X980983Y1140917D01*
X981275Y1141000D01*
X981608D01*
X981983Y1140875D01*
X982275Y1140667D01*
X982483Y1140417D01*
X982650Y1140000D01*
X982692Y1139625D01*
X982608Y1139250D01*
X982483Y1139000D01*
X982233Y1138750D01*
X981942Y1138583D01*
X981650Y1138500D01*
X981358D01*
X981067Y1138583D01*
X980817Y1138708D01*
X980608Y1138875D01*
G01X979342Y1139542D02*
X979050Y1139833D01*
X978800Y1140000D01*
X978467Y1140083D01*
X978175Y1140000D01*
X977967Y1139833D01*
X977800Y1139583D01*
X977758Y1139292D01*
X977800Y1139042D01*
X977967Y1138792D01*
X978217Y1138583D01*
X978508Y1138500D01*
X978842Y1138583D01*
X979133Y1138833D01*
X979300Y1139208D01*
X979342Y1139625D01*
X979258Y1140167D01*
X979133Y1140458D01*
X978925Y1140750D01*
X978633Y1140958D01*
X978342Y1141000D01*
X978050Y1140917D01*
X977842Y1140708D01*
G01X976158Y1138792D02*
X975867Y1138583D01*
X975533Y1138500D01*
X975200Y1138583D01*
X974908Y1138833D01*
X974700Y1139208D01*
X974617Y1139583D01*
Y1140042D01*
X974700Y1140417D01*
X974908Y1140750D01*
X975158Y1140917D01*
X975450Y1141000D01*
X975783Y1140917D01*
X976033Y1140750D01*
X976200Y1140500D01*
X976283Y1140167D01*
X976200Y1139875D01*
X975992Y1139583D01*
X975742Y1139417D01*
X975450Y1139375D01*
X975117Y1139458D01*
X974867Y1139667D01*
X974617Y1140042D01*
G01X971850Y1138500D02*
Y1141000D01*
X973392Y1139208D01*
X971308D01*
G01X965392Y1139867D02*
X965517Y1139617D01*
X965600Y1139325D01*
Y1138992D01*
X965475Y1138617D01*
X965267Y1138325D01*
X965017Y1138117D01*
X964600Y1137950D01*
X964225Y1137908D01*
X963850Y1137992D01*
X963600Y1138117D01*
X963350Y1138367D01*
X963183Y1138658D01*
X963100Y1138950D01*
Y1139242D01*
X963183Y1139533D01*
X963308Y1139783D01*
X963475Y1139992D01*
G01X964142Y1141258D02*
X964433Y1141550D01*
X964600Y1141800D01*
X964683Y1142133D01*
X964600Y1142425D01*
X964433Y1142633D01*
X964183Y1142800D01*
X963892Y1142842D01*
X963642Y1142800D01*
X963392Y1142633D01*
X963183Y1142383D01*
X963100Y1142092D01*
X963183Y1141758D01*
X963433Y1141467D01*
X963808Y1141300D01*
X964225Y1141258D01*
X964767Y1141342D01*
X965058Y1141467D01*
X965350Y1141675D01*
X965558Y1141967D01*
X965600Y1142258D01*
X965517Y1142550D01*
X965308Y1142758D01*
G01X963392Y1144442D02*
X963183Y1144733D01*
X963100Y1145067D01*
X963183Y1145400D01*
X963433Y1145692D01*
X963808Y1145900D01*
X964183Y1145983D01*
X964642D01*
X965017Y1145900D01*
X965350Y1145692D01*
X965517Y1145442D01*
X965600Y1145150D01*
X965517Y1144817D01*
X965350Y1144567D01*
X965100Y1144400D01*
X964767Y1144317D01*
X964475Y1144400D01*
X964183Y1144608D01*
X964017Y1144858D01*
X963975Y1145150D01*
X964058Y1145483D01*
X964267Y1145733D01*
X964642Y1145983D01*
G01X963100Y1148250D02*
X963142Y1148542D01*
X963267Y1148875D01*
X963475Y1149083D01*
X963767Y1149167D01*
X964058Y1149083D01*
X964308Y1148833D01*
X964433Y1148458D01*
Y1148042D01*
X964517Y1147792D01*
X964725Y1147583D01*
X965017Y1147500D01*
X965308Y1147625D01*
X965517Y1147917D01*
X965600Y1148250D01*
X965517Y1148583D01*
X965308Y1148875D01*
X965017Y1149000D01*
X964725Y1148917D01*
X964517Y1148708D01*
X964433Y1148458D01*
Y1148042D01*
X964308Y1147667D01*
X964058Y1147417D01*
X963767Y1147333D01*
X963475Y1147417D01*
X963267Y1147625D01*
X963142Y1147958D01*
X963100Y1148250D01*
G01X1051700Y1099500D02*
Y1097000D01*
G01X1052658Y1099500D02*
X1050742D01*
G01X1049433Y1097000D02*
Y1099500D01*
X1048433D01*
X1048100Y1099375D01*
X1047850Y1099083D01*
X1047767Y1098750D01*
X1047850Y1098417D01*
X1048058Y1098167D01*
X1048433Y1098042D01*
X1049433D01*
G01X1046292Y1099083D02*
X1046042Y1099333D01*
X1045750Y1099458D01*
X1045417Y1099500D01*
X1045000Y1099417D01*
X1044708Y1099208D01*
X1044625Y1098958D01*
X1044667Y1098708D01*
X1044833Y1098500D01*
X1045667Y1098083D01*
X1046042Y1097792D01*
X1046292Y1097375D01*
X1046375Y1097000D01*
X1044625D01*
G01X1042400Y1099500D02*
X1042733Y1099417D01*
X1042983Y1099208D01*
X1043150Y1098958D01*
X1043275Y1098625D01*
X1043317Y1098250D01*
X1043275Y1097875D01*
X1043150Y1097542D01*
X1042983Y1097292D01*
X1042733Y1097083D01*
X1042400Y1097000D01*
X1042067Y1097083D01*
X1041817Y1097292D01*
X1041650Y1097542D01*
X1041525Y1097875D01*
X1041483Y1098250D01*
X1041525Y1098625D01*
X1041650Y1098958D01*
X1041817Y1099208D01*
X1042067Y1099417D01*
X1042400Y1099500D01*
G01X1040092Y1098042D02*
X1039800Y1098333D01*
X1039550Y1098500D01*
X1039217Y1098583D01*
X1038925Y1098500D01*
X1038717Y1098333D01*
X1038550Y1098083D01*
X1038508Y1097792D01*
X1038550Y1097542D01*
X1038717Y1097292D01*
X1038967Y1097083D01*
X1039258Y1097000D01*
X1039592Y1097083D01*
X1039883Y1097333D01*
X1040050Y1097708D01*
X1040092Y1098125D01*
X1040008Y1098667D01*
X1039883Y1098958D01*
X1039675Y1099250D01*
X1039383Y1099458D01*
X1039092Y1099500D01*
X1038800Y1099417D01*
X1038592Y1099208D01*
G01X1025800Y1093250D02*
X1024967D01*
Y1092500D01*
X1025217Y1092250D01*
X1025508Y1092083D01*
X1025925Y1092000D01*
X1026342Y1092083D01*
X1026633Y1092250D01*
X1026883Y1092500D01*
X1027050Y1092792D01*
X1027133Y1093125D01*
Y1093417D01*
X1027050Y1093667D01*
X1026883Y1093958D01*
X1026633Y1094208D01*
X1026383Y1094375D01*
X1026050Y1094500D01*
X1025758D01*
X1025425Y1094417D01*
X1025175Y1094250D01*
G01X1023658Y1092292D02*
X1023367Y1092083D01*
X1023033Y1092000D01*
X1022700Y1092083D01*
X1022408Y1092333D01*
X1022200Y1092708D01*
X1022117Y1093083D01*
Y1093542D01*
X1022200Y1093917D01*
X1022408Y1094250D01*
X1022658Y1094417D01*
X1022950Y1094500D01*
X1023283Y1094417D01*
X1023533Y1094250D01*
X1023700Y1094000D01*
X1023783Y1093667D01*
X1023700Y1093375D01*
X1023492Y1093083D01*
X1023242Y1092917D01*
X1022950Y1092875D01*
X1022617Y1092958D01*
X1022367Y1093167D01*
X1022117Y1093542D01*
G01X986883Y1086000D02*
Y1083500D01*
X985217D01*
G01X983658Y1083792D02*
X983367Y1083583D01*
X983033Y1083500D01*
X982700Y1083583D01*
X982408Y1083833D01*
X982200Y1084208D01*
X982117Y1084583D01*
Y1085042D01*
X982200Y1085417D01*
X982408Y1085750D01*
X982658Y1085917D01*
X982950Y1086000D01*
X983283Y1085917D01*
X983533Y1085750D01*
X983700Y1085500D01*
X983783Y1085167D01*
X983700Y1084875D01*
X983492Y1084583D01*
X983242Y1084417D01*
X982950Y1084375D01*
X982617Y1084458D01*
X982367Y1084667D01*
X982117Y1085042D01*
G01X998700Y1148000D02*
Y1140000D01*
X1016300D01*
Y1148000D01*
X998700D01*
G01X1014017Y1128600D02*
Y1126808D01*
X1013850Y1126433D01*
X1013517Y1126183D01*
X1013100Y1126100D01*
X1012683Y1126183D01*
X1012350Y1126433D01*
X1012183Y1126808D01*
Y1128600D01*
G01X1010917Y1126600D02*
X1010667Y1126308D01*
X1010333Y1126142D01*
X1009958Y1126100D01*
X1009625Y1126142D01*
X1009292Y1126350D01*
X1009083Y1126600D01*
X1009042Y1126850D01*
X1009125Y1127142D01*
X1009417Y1127350D01*
X1009708Y1127433D01*
X1010083D01*
G01X1009708D02*
X1009458Y1127558D01*
X1009250Y1127767D01*
X1009167Y1128017D01*
X1009250Y1128267D01*
X1009458Y1128475D01*
X1009833Y1128600D01*
X1010208Y1128558D01*
X1010583Y1128392D01*
G01X1007817Y1126475D02*
X1007567Y1126267D01*
X1007275Y1126142D01*
X1006900Y1126100D01*
X1006525Y1126183D01*
X1006233Y1126350D01*
X1006025Y1126642D01*
X1005983Y1126975D01*
X1006067Y1127308D01*
X1006275Y1127517D01*
X1006567Y1127683D01*
X1006858Y1127725D01*
X1007150Y1127683D01*
X1007525Y1127517D01*
X1007400Y1128600D01*
X1006275D01*
G01X991787Y1116399D02*
Y1121399D01*
X996787D01*
G01Y1101599D02*
X991787D01*
Y1106599D01*
G01X1011587D02*
Y1101599D01*
X1006587D01*
G01X1002671Y1120405D02*
Y1122405D01*
G01X1004640Y1102593D02*
Y1100593D01*
G01X992781Y1110515D02*
X989781D01*
G01X970700Y1086000D02*
X965500D01*
G01X970700Y1079000D02*
X962900D01*
G01X970700Y1086000D02*
Y1079000D01*
G01X994233Y1152292D02*
X994483Y1152417D01*
X994775Y1152500D01*
X995108D01*
X995483Y1152375D01*
X995775Y1152167D01*
X995983Y1151917D01*
X996150Y1151500D01*
X996192Y1151125D01*
X996108Y1150750D01*
X995983Y1150500D01*
X995733Y1150250D01*
X995442Y1150083D01*
X995150Y1150000D01*
X994858D01*
X994567Y1150083D01*
X994317Y1150208D01*
X994108Y1150375D01*
G01X992842Y1151042D02*
X992550Y1151333D01*
X992300Y1151500D01*
X991967Y1151583D01*
X991675Y1151500D01*
X991467Y1151333D01*
X991300Y1151083D01*
X991258Y1150792D01*
X991300Y1150542D01*
X991467Y1150292D01*
X991717Y1150083D01*
X992008Y1150000D01*
X992342Y1150083D01*
X992633Y1150333D01*
X992800Y1150708D01*
X992842Y1151125D01*
X992758Y1151667D01*
X992633Y1151958D01*
X992425Y1152250D01*
X992133Y1152458D01*
X991842Y1152500D01*
X991550Y1152417D01*
X991342Y1152208D01*
G01X989658Y1150292D02*
X989367Y1150083D01*
X989033Y1150000D01*
X988700Y1150083D01*
X988408Y1150333D01*
X988200Y1150708D01*
X988117Y1151083D01*
Y1151542D01*
X988200Y1151917D01*
X988408Y1152250D01*
X988658Y1152417D01*
X988950Y1152500D01*
X989283Y1152417D01*
X989533Y1152250D01*
X989700Y1152000D01*
X989783Y1151667D01*
X989700Y1151375D01*
X989492Y1151083D01*
X989242Y1150917D01*
X988950Y1150875D01*
X988617Y1150958D01*
X988367Y1151167D01*
X988117Y1151542D01*
G01X985850Y1152500D02*
X986183Y1152417D01*
X986433Y1152208D01*
X986600Y1151958D01*
X986725Y1151625D01*
X986767Y1151250D01*
X986725Y1150875D01*
X986600Y1150542D01*
X986433Y1150292D01*
X986183Y1150083D01*
X985850Y1150000D01*
X985517Y1150083D01*
X985267Y1150292D01*
X985100Y1150542D01*
X984975Y1150875D01*
X984933Y1151250D01*
X984975Y1151625D01*
X985100Y1151958D01*
X985267Y1152208D01*
X985517Y1152417D01*
X985850Y1152500D01*
G01X1022000Y1146967D02*
X1024500D01*
Y1148008D01*
X1024375Y1148342D01*
X1024208Y1148550D01*
X1023875Y1148633D01*
X1023542Y1148550D01*
X1023333Y1148300D01*
X1023208Y1148008D01*
Y1146967D01*
G01Y1148008D02*
X1022000Y1148633D01*
G01Y1150900D02*
X1024500D01*
X1024000Y1150400D01*
G01X1022000D02*
Y1151400D01*
G01Y1154000D02*
X1024500D01*
X1024000Y1153500D01*
G01X1022000D02*
Y1154500D01*
G01Y1157017D02*
X1022542Y1157100D01*
X1023000Y1157225D01*
X1023417Y1157392D01*
X1023875Y1157600D01*
X1024500Y1157933D01*
Y1156267D01*
G01X1023042Y1159408D02*
X1023333Y1159700D01*
X1023500Y1159950D01*
X1023583Y1160283D01*
X1023500Y1160575D01*
X1023333Y1160783D01*
X1023083Y1160950D01*
X1022792Y1160992D01*
X1022542Y1160950D01*
X1022292Y1160783D01*
X1022083Y1160533D01*
X1022000Y1160242D01*
X1022083Y1159908D01*
X1022333Y1159617D01*
X1022708Y1159450D01*
X1023125Y1159408D01*
X1023667Y1159492D01*
X1023958Y1159617D01*
X1024250Y1159825D01*
X1024458Y1160117D01*
X1024500Y1160408D01*
X1024417Y1160700D01*
X1024208Y1160908D01*
G01X994233Y1156292D02*
X994483Y1156417D01*
X994775Y1156500D01*
X995108D01*
X995483Y1156375D01*
X995775Y1156167D01*
X995983Y1155917D01*
X996150Y1155500D01*
X996192Y1155125D01*
X996108Y1154750D01*
X995983Y1154500D01*
X995733Y1154250D01*
X995442Y1154083D01*
X995150Y1154000D01*
X994858D01*
X994567Y1154083D01*
X994317Y1154208D01*
X994108Y1154375D01*
G01X992842Y1155042D02*
X992550Y1155333D01*
X992300Y1155500D01*
X991967Y1155583D01*
X991675Y1155500D01*
X991467Y1155333D01*
X991300Y1155083D01*
X991258Y1154792D01*
X991300Y1154542D01*
X991467Y1154292D01*
X991717Y1154083D01*
X992008Y1154000D01*
X992342Y1154083D01*
X992633Y1154333D01*
X992800Y1154708D01*
X992842Y1155125D01*
X992758Y1155667D01*
X992633Y1155958D01*
X992425Y1156250D01*
X992133Y1156458D01*
X991842Y1156500D01*
X991550Y1156417D01*
X991342Y1156208D01*
G01X989658Y1154292D02*
X989367Y1154083D01*
X989033Y1154000D01*
X988700Y1154083D01*
X988408Y1154333D01*
X988200Y1154708D01*
X988117Y1155083D01*
Y1155542D01*
X988200Y1155917D01*
X988408Y1156250D01*
X988658Y1156417D01*
X988950Y1156500D01*
X989283Y1156417D01*
X989533Y1156250D01*
X989700Y1156000D01*
X989783Y1155667D01*
X989700Y1155375D01*
X989492Y1155083D01*
X989242Y1154917D01*
X988950Y1154875D01*
X988617Y1154958D01*
X988367Y1155167D01*
X988117Y1155542D01*
G01X985850Y1154000D02*
Y1156500D01*
X986350Y1156000D01*
G01Y1154000D02*
X985350D01*
G01X994233Y1160292D02*
X994483Y1160417D01*
X994775Y1160500D01*
X995108D01*
X995483Y1160375D01*
X995775Y1160167D01*
X995983Y1159917D01*
X996150Y1159500D01*
X996192Y1159125D01*
X996108Y1158750D01*
X995983Y1158500D01*
X995733Y1158250D01*
X995442Y1158083D01*
X995150Y1158000D01*
X994858D01*
X994567Y1158083D01*
X994317Y1158208D01*
X994108Y1158375D01*
G01X992842Y1159042D02*
X992550Y1159333D01*
X992300Y1159500D01*
X991967Y1159583D01*
X991675Y1159500D01*
X991467Y1159333D01*
X991300Y1159083D01*
X991258Y1158792D01*
X991300Y1158542D01*
X991467Y1158292D01*
X991717Y1158083D01*
X992008Y1158000D01*
X992342Y1158083D01*
X992633Y1158333D01*
X992800Y1158708D01*
X992842Y1159125D01*
X992758Y1159667D01*
X992633Y1159958D01*
X992425Y1160250D01*
X992133Y1160458D01*
X991842Y1160500D01*
X991550Y1160417D01*
X991342Y1160208D01*
G01X989658Y1158292D02*
X989367Y1158083D01*
X989033Y1158000D01*
X988700Y1158083D01*
X988408Y1158333D01*
X988200Y1158708D01*
X988117Y1159083D01*
Y1159542D01*
X988200Y1159917D01*
X988408Y1160250D01*
X988658Y1160417D01*
X988950Y1160500D01*
X989283Y1160417D01*
X989533Y1160250D01*
X989700Y1160000D01*
X989783Y1159667D01*
X989700Y1159375D01*
X989492Y1159083D01*
X989242Y1158917D01*
X988950Y1158875D01*
X988617Y1158958D01*
X988367Y1159167D01*
X988117Y1159542D01*
G01X986767Y1158500D02*
X986517Y1158208D01*
X986183Y1158042D01*
X985808Y1158000D01*
X985475Y1158042D01*
X985142Y1158250D01*
X984933Y1158500D01*
X984892Y1158750D01*
X984975Y1159042D01*
X985267Y1159250D01*
X985558Y1159333D01*
X985933D01*
G01X985558D02*
X985308Y1159458D01*
X985100Y1159667D01*
X985017Y1159917D01*
X985100Y1160167D01*
X985308Y1160375D01*
X985683Y1160500D01*
X986058Y1160458D01*
X986433Y1160292D01*
G01X1017033Y1155000D02*
Y1157500D01*
X1015992D01*
X1015658Y1157375D01*
X1015450Y1157208D01*
X1015367Y1156875D01*
X1015450Y1156542D01*
X1015700Y1156333D01*
X1015992Y1156208D01*
X1017033D01*
G01X1015992D02*
X1015367Y1155000D01*
G01X1013100D02*
Y1157500D01*
X1013600Y1157000D01*
G01Y1155000D02*
X1012600D01*
G01X1010000D02*
Y1157500D01*
X1010500Y1157000D01*
G01Y1155000D02*
X1009500D01*
G01X1006983D02*
X1006900Y1155542D01*
X1006775Y1156000D01*
X1006608Y1156417D01*
X1006400Y1156875D01*
X1006067Y1157500D01*
X1007733D01*
G01X1003300Y1155000D02*
Y1157500D01*
X1004842Y1155708D01*
X1002758D01*
G01X1680025Y200333D02*
X1679692Y200125D01*
X1679317Y200000D01*
X1678983D01*
X1678650Y200125D01*
X1678400Y200333D01*
X1678275Y200625D01*
X1678358Y200917D01*
X1678567Y201167D01*
X1678942Y201333D01*
X1679442Y201417D01*
X1679733Y201583D01*
X1679858Y201875D01*
X1679775Y202167D01*
X1679567Y202375D01*
X1679275Y202500D01*
X1678983D01*
X1678692Y202417D01*
X1678442Y202208D01*
G01X1675133Y202292D02*
X1675383Y202417D01*
X1675675Y202500D01*
X1676008D01*
X1676383Y202375D01*
X1676675Y202167D01*
X1676883Y201917D01*
X1677050Y201500D01*
X1677092Y201125D01*
X1677008Y200750D01*
X1676883Y200500D01*
X1676633Y200250D01*
X1676342Y200083D01*
X1676050Y200000D01*
X1675758D01*
X1675467Y200083D01*
X1675217Y200208D01*
X1675008Y200375D01*
G01X1674200Y202500D02*
X1673617Y200000D01*
X1672950Y202500D01*
X1672283Y200000D01*
X1671700Y202500D01*
G01X1670642Y202083D02*
X1670392Y202333D01*
X1670100Y202458D01*
X1669767Y202500D01*
X1669350Y202417D01*
X1669058Y202208D01*
X1668975Y201958D01*
X1669017Y201708D01*
X1669183Y201500D01*
X1670017Y201083D01*
X1670392Y200792D01*
X1670642Y200375D01*
X1670725Y200000D01*
X1668975D01*
G01X1706188Y429849D02*
X1706313Y429599D01*
X1706396Y429307D01*
Y428974D01*
X1706271Y428599D01*
X1706063Y428307D01*
X1705813Y428099D01*
X1705396Y427932D01*
X1705021Y427890D01*
X1704646Y427974D01*
X1704396Y428099D01*
X1704146Y428349D01*
X1703979Y428640D01*
X1703896Y428932D01*
Y429224D01*
X1703979Y429515D01*
X1704104Y429765D01*
X1704271Y429974D01*
G01X1704938Y431240D02*
X1705229Y431532D01*
X1705396Y431782D01*
X1705479Y432115D01*
X1705396Y432407D01*
X1705229Y432615D01*
X1704979Y432782D01*
X1704688Y432824D01*
X1704438Y432782D01*
X1704188Y432615D01*
X1703979Y432365D01*
X1703896Y432074D01*
X1703979Y431740D01*
X1704229Y431449D01*
X1704604Y431282D01*
X1705021Y431240D01*
X1705563Y431324D01*
X1705854Y431449D01*
X1706146Y431657D01*
X1706354Y431949D01*
X1706396Y432240D01*
X1706313Y432532D01*
X1706104Y432740D01*
G01X1703896Y435049D02*
X1704438Y435132D01*
X1704896Y435257D01*
X1705313Y435424D01*
X1705771Y435632D01*
X1706396Y435965D01*
Y434299D01*
G01X1703896Y438732D02*
X1706396D01*
X1704604Y437190D01*
Y439274D01*
G01X1704329Y467474D02*
X1704579Y467599D01*
X1704871Y467682D01*
X1705204D01*
X1705579Y467557D01*
X1705871Y467349D01*
X1706079Y467099D01*
X1706246Y466682D01*
X1706288Y466307D01*
X1706204Y465932D01*
X1706079Y465682D01*
X1705829Y465432D01*
X1705538Y465265D01*
X1705246Y465182D01*
X1704954D01*
X1704663Y465265D01*
X1704413Y465390D01*
X1704204Y465557D01*
G01X1702938Y466224D02*
X1702646Y466515D01*
X1702396Y466682D01*
X1702063Y466765D01*
X1701771Y466682D01*
X1701563Y466515D01*
X1701396Y466265D01*
X1701354Y465974D01*
X1701396Y465724D01*
X1701563Y465474D01*
X1701813Y465265D01*
X1702104Y465182D01*
X1702438Y465265D01*
X1702729Y465515D01*
X1702896Y465890D01*
X1702938Y466307D01*
X1702854Y466849D01*
X1702729Y467140D01*
X1702521Y467432D01*
X1702229Y467640D01*
X1701938Y467682D01*
X1701646Y467599D01*
X1701438Y467390D01*
G01X1699046Y465182D02*
X1698754Y465224D01*
X1698421Y465349D01*
X1698213Y465557D01*
X1698129Y465849D01*
X1698213Y466140D01*
X1698463Y466390D01*
X1698838Y466515D01*
X1699254D01*
X1699504Y466599D01*
X1699713Y466807D01*
X1699796Y467099D01*
X1699671Y467390D01*
X1699379Y467599D01*
X1699046Y467682D01*
X1698713Y467599D01*
X1698421Y467390D01*
X1698296Y467099D01*
X1698379Y466807D01*
X1698588Y466599D01*
X1698838Y466515D01*
X1699254D01*
X1699629Y466390D01*
X1699879Y466140D01*
X1699963Y465849D01*
X1699879Y465557D01*
X1699671Y465349D01*
X1699338Y465224D01*
X1699046Y465182D01*
G01X1695946D02*
Y467682D01*
X1696446Y467182D01*
G01Y465182D02*
X1695446D01*
G01X1671596Y448649D02*
X1674096D01*
Y449690D01*
X1673971Y450024D01*
X1673804Y450232D01*
X1673471Y450315D01*
X1673138Y450232D01*
X1672929Y449982D01*
X1672804Y449690D01*
Y448649D01*
G01Y449690D02*
X1671596Y450315D01*
G01Y452582D02*
X1674096D01*
X1673596Y452082D01*
G01X1671596D02*
Y453082D01*
G01Y455682D02*
X1674096D01*
X1673596Y455182D01*
G01X1671596D02*
Y456182D01*
G01X1671971Y457865D02*
X1671763Y458115D01*
X1671638Y458407D01*
X1671596Y458782D01*
X1671679Y459157D01*
X1671846Y459449D01*
X1672138Y459657D01*
X1672471Y459699D01*
X1672804Y459615D01*
X1673013Y459407D01*
X1673179Y459115D01*
X1673221Y458824D01*
X1673179Y458532D01*
X1673013Y458157D01*
X1674096Y458282D01*
Y459407D01*
G01X1672638Y461090D02*
X1672929Y461382D01*
X1673096Y461632D01*
X1673179Y461965D01*
X1673096Y462257D01*
X1672929Y462465D01*
X1672679Y462632D01*
X1672388Y462674D01*
X1672138Y462632D01*
X1671888Y462465D01*
X1671679Y462215D01*
X1671596Y461924D01*
X1671679Y461590D01*
X1671929Y461299D01*
X1672304Y461132D01*
X1672721Y461090D01*
X1673263Y461174D01*
X1673554Y461299D01*
X1673846Y461507D01*
X1674054Y461799D01*
X1674096Y462090D01*
X1674013Y462382D01*
X1673804Y462590D01*
G01X1701088Y426749D02*
X1701213Y426499D01*
X1701296Y426207D01*
Y425874D01*
X1701171Y425499D01*
X1700963Y425207D01*
X1700713Y424999D01*
X1700296Y424832D01*
X1699921Y424790D01*
X1699546Y424874D01*
X1699296Y424999D01*
X1699046Y425249D01*
X1698879Y425540D01*
X1698796Y425832D01*
Y426124D01*
X1698879Y426415D01*
X1699004Y426665D01*
X1699171Y426874D01*
G01X1699838Y428140D02*
X1700129Y428432D01*
X1700296Y428682D01*
X1700379Y429015D01*
X1700296Y429307D01*
X1700129Y429515D01*
X1699879Y429682D01*
X1699588Y429724D01*
X1699338Y429682D01*
X1699088Y429515D01*
X1698879Y429265D01*
X1698796Y428974D01*
X1698879Y428640D01*
X1699129Y428349D01*
X1699504Y428182D01*
X1699921Y428140D01*
X1700463Y428224D01*
X1700754Y428349D01*
X1701046Y428557D01*
X1701254Y428849D01*
X1701296Y429140D01*
X1701213Y429432D01*
X1701004Y429640D01*
G01X1698796Y431949D02*
X1699338Y432032D01*
X1699796Y432157D01*
X1700213Y432324D01*
X1700671Y432532D01*
X1701296Y432865D01*
Y431199D01*
G01X1698796Y435132D02*
X1701296D01*
X1700796Y434632D01*
G01X1698796D02*
Y435632D01*
G01X1688188Y425649D02*
X1688313Y425399D01*
X1688396Y425107D01*
Y424774D01*
X1688271Y424399D01*
X1688063Y424107D01*
X1687813Y423899D01*
X1687396Y423732D01*
X1687021Y423690D01*
X1686646Y423774D01*
X1686396Y423899D01*
X1686146Y424149D01*
X1685979Y424440D01*
X1685896Y424732D01*
Y425024D01*
X1685979Y425315D01*
X1686104Y425565D01*
X1686271Y425774D01*
G01X1686938Y427040D02*
X1687229Y427332D01*
X1687396Y427582D01*
X1687479Y427915D01*
X1687396Y428207D01*
X1687229Y428415D01*
X1686979Y428582D01*
X1686688Y428624D01*
X1686438Y428582D01*
X1686188Y428415D01*
X1685979Y428165D01*
X1685896Y427874D01*
X1685979Y427540D01*
X1686229Y427249D01*
X1686604Y427082D01*
X1687021Y427040D01*
X1687563Y427124D01*
X1687854Y427249D01*
X1688146Y427457D01*
X1688354Y427749D01*
X1688396Y428040D01*
X1688313Y428332D01*
X1688104Y428540D01*
G01X1685896Y430849D02*
X1686438Y430932D01*
X1686896Y431057D01*
X1687313Y431224D01*
X1687771Y431432D01*
X1688396Y431765D01*
Y430099D01*
G01X1687979Y433240D02*
X1688229Y433490D01*
X1688354Y433782D01*
X1688396Y434115D01*
X1688313Y434532D01*
X1688104Y434824D01*
X1687854Y434907D01*
X1687604Y434865D01*
X1687396Y434699D01*
X1686979Y433865D01*
X1686688Y433490D01*
X1686271Y433240D01*
X1685896Y433157D01*
Y434907D01*
G01X1681388Y457449D02*
X1681513Y457199D01*
X1681596Y456907D01*
Y456574D01*
X1681471Y456199D01*
X1681263Y455907D01*
X1681013Y455699D01*
X1680596Y455532D01*
X1680221Y455490D01*
X1679846Y455574D01*
X1679596Y455699D01*
X1679346Y455949D01*
X1679179Y456240D01*
X1679096Y456532D01*
Y456824D01*
X1679179Y457115D01*
X1679304Y457365D01*
X1679471Y457574D01*
G01X1680138Y458840D02*
X1680429Y459132D01*
X1680596Y459382D01*
X1680679Y459715D01*
X1680596Y460007D01*
X1680429Y460215D01*
X1680179Y460382D01*
X1679888Y460424D01*
X1679638Y460382D01*
X1679388Y460215D01*
X1679179Y459965D01*
X1679096Y459674D01*
X1679179Y459340D01*
X1679429Y459049D01*
X1679804Y458882D01*
X1680221Y458840D01*
X1680763Y458924D01*
X1681054Y459049D01*
X1681346Y459257D01*
X1681554Y459549D01*
X1681596Y459840D01*
X1681513Y460132D01*
X1681304Y460340D01*
G01X1679096Y462649D02*
X1679638Y462732D01*
X1680096Y462857D01*
X1680513Y463024D01*
X1680971Y463232D01*
X1681596Y463565D01*
Y461899D01*
G01X1679596Y464915D02*
X1679304Y465165D01*
X1679138Y465499D01*
X1679096Y465874D01*
X1679138Y466207D01*
X1679346Y466540D01*
X1679596Y466749D01*
X1679846Y466790D01*
X1680138Y466707D01*
X1680346Y466415D01*
X1680429Y466124D01*
Y465749D01*
G01Y466124D02*
X1680554Y466374D01*
X1680763Y466582D01*
X1681013Y466665D01*
X1681263Y466582D01*
X1681471Y466374D01*
X1681596Y465999D01*
X1681554Y465624D01*
X1681388Y465249D01*
G01X1704329Y471974D02*
X1704579Y472099D01*
X1704871Y472182D01*
X1705204D01*
X1705579Y472057D01*
X1705871Y471849D01*
X1706079Y471599D01*
X1706246Y471182D01*
X1706288Y470807D01*
X1706204Y470432D01*
X1706079Y470182D01*
X1705829Y469932D01*
X1705538Y469765D01*
X1705246Y469682D01*
X1704954D01*
X1704663Y469765D01*
X1704413Y469890D01*
X1704204Y470057D01*
G01X1702938Y470724D02*
X1702646Y471015D01*
X1702396Y471182D01*
X1702063Y471265D01*
X1701771Y471182D01*
X1701563Y471015D01*
X1701396Y470765D01*
X1701354Y470474D01*
X1701396Y470224D01*
X1701563Y469974D01*
X1701813Y469765D01*
X1702104Y469682D01*
X1702438Y469765D01*
X1702729Y470015D01*
X1702896Y470390D01*
X1702938Y470807D01*
X1702854Y471349D01*
X1702729Y471640D01*
X1702521Y471932D01*
X1702229Y472140D01*
X1701938Y472182D01*
X1701646Y472099D01*
X1701438Y471890D01*
G01X1699129Y469682D02*
X1699046Y470224D01*
X1698921Y470682D01*
X1698754Y471099D01*
X1698546Y471557D01*
X1698213Y472182D01*
X1699879D01*
G01X1695946Y469682D02*
X1695654Y469724D01*
X1695321Y469849D01*
X1695113Y470057D01*
X1695029Y470349D01*
X1695113Y470640D01*
X1695363Y470890D01*
X1695738Y471015D01*
X1696154D01*
X1696404Y471099D01*
X1696613Y471307D01*
X1696696Y471599D01*
X1696571Y471890D01*
X1696279Y472099D01*
X1695946Y472182D01*
X1695613Y472099D01*
X1695321Y471890D01*
X1695196Y471599D01*
X1695279Y471307D01*
X1695488Y471099D01*
X1695738Y471015D01*
X1696154D01*
X1696529Y470890D01*
X1696779Y470640D01*
X1696863Y470349D01*
X1696779Y470057D01*
X1696571Y469849D01*
X1696238Y469724D01*
X1695946Y469682D01*
G01X1680163Y427485D02*
Y424985D01*
X1678497D01*
G01X1676313D02*
X1676230Y425527D01*
X1676105Y425985D01*
X1675938Y426402D01*
X1675730Y426860D01*
X1675397Y427485D01*
X1677063D01*
G01X1683559Y428607D02*
X1670159D01*
G01X1683559Y435807D02*
Y428607D01*
G01X1670159Y435807D02*
X1683559D01*
G01X1670159Y428607D02*
Y435807D01*
G01X1711746Y460182D02*
Y465182D01*
X1716746D01*
G01Y437182D02*
X1711746D01*
Y442182D01*
G01X1712753Y457088D02*
X1709753D01*
G01X1712753Y447245D02*
X1710753D01*
G01X1720696Y480249D02*
X1723196D01*
Y481290D01*
X1723071Y481624D01*
X1722904Y481832D01*
X1722571Y481915D01*
X1722238Y481832D01*
X1722029Y481582D01*
X1721904Y481290D01*
Y480249D01*
G01Y481290D02*
X1720696Y481915D01*
G01Y484182D02*
X1723196D01*
X1722696Y483682D01*
G01X1720696D02*
Y484682D01*
G01Y487282D02*
X1723196D01*
X1722696Y486782D01*
G01X1720696D02*
Y487782D01*
G01Y490299D02*
X1721238Y490382D01*
X1721696Y490507D01*
X1722113Y490674D01*
X1722571Y490882D01*
X1723196Y491215D01*
Y489549D01*
G01X1720696Y493482D02*
X1723196D01*
X1722696Y492982D01*
G01X1720696D02*
Y493982D01*
G01X1716996Y481032D02*
X1716163D01*
Y480282D01*
X1716413Y480032D01*
X1716704Y479865D01*
X1717121Y479782D01*
X1717538Y479865D01*
X1717829Y480032D01*
X1718079Y480282D01*
X1718246Y480574D01*
X1718329Y480907D01*
Y481199D01*
X1718246Y481449D01*
X1718079Y481740D01*
X1717829Y481990D01*
X1717579Y482157D01*
X1717246Y482282D01*
X1716954D01*
X1716621Y482199D01*
X1716371Y482032D01*
G01X1714146Y479782D02*
X1713854Y479824D01*
X1713521Y479949D01*
X1713313Y480157D01*
X1713229Y480449D01*
X1713313Y480740D01*
X1713563Y480990D01*
X1713938Y481115D01*
X1714354D01*
X1714604Y481199D01*
X1714813Y481407D01*
X1714896Y481699D01*
X1714771Y481990D01*
X1714479Y482199D01*
X1714146Y482282D01*
X1713813Y482199D01*
X1713521Y481990D01*
X1713396Y481699D01*
X1713479Y481407D01*
X1713688Y481199D01*
X1713938Y481115D01*
X1714354D01*
X1714729Y480990D01*
X1714979Y480740D01*
X1715063Y480449D01*
X1714979Y480157D01*
X1714771Y479949D01*
X1714438Y479824D01*
X1714146Y479782D01*
G01X1771496Y463949D02*
X1773996D01*
Y464990D01*
X1773871Y465324D01*
X1773704Y465532D01*
X1773371Y465615D01*
X1773038Y465532D01*
X1772829Y465282D01*
X1772704Y464990D01*
Y463949D01*
G01Y464990D02*
X1771496Y465615D01*
G01Y467882D02*
X1773996D01*
X1773496Y467382D01*
G01X1771496D02*
Y468382D01*
G01Y470982D02*
X1773996D01*
X1773496Y470482D01*
G01X1771496D02*
Y471482D01*
G01X1772538Y473290D02*
X1772829Y473582D01*
X1772996Y473832D01*
X1773079Y474165D01*
X1772996Y474457D01*
X1772829Y474665D01*
X1772579Y474832D01*
X1772288Y474874D01*
X1772038Y474832D01*
X1771788Y474665D01*
X1771579Y474415D01*
X1771496Y474124D01*
X1771579Y473790D01*
X1771829Y473499D01*
X1772204Y473332D01*
X1772621Y473290D01*
X1773163Y473374D01*
X1773454Y473499D01*
X1773746Y473707D01*
X1773954Y473999D01*
X1773996Y474290D01*
X1773913Y474582D01*
X1773704Y474790D01*
G01X1773996Y477182D02*
X1773913Y476849D01*
X1773704Y476599D01*
X1773454Y476432D01*
X1773121Y476307D01*
X1772746Y476265D01*
X1772371Y476307D01*
X1772038Y476432D01*
X1771788Y476599D01*
X1771579Y476849D01*
X1771496Y477182D01*
X1771579Y477515D01*
X1771788Y477765D01*
X1772038Y477932D01*
X1772371Y478057D01*
X1772746Y478099D01*
X1773121Y478057D01*
X1773454Y477932D01*
X1773704Y477765D01*
X1773913Y477515D01*
X1773996Y477182D01*
G01X1764332Y463956D02*
X1760332D01*
Y471356D01*
G01X1731537Y465698D02*
X1727537D01*
Y473098D01*
G01X1733196Y467982D02*
Y471982D01*
X1740596D01*
G01X1778288Y465749D02*
X1778413Y465499D01*
X1778496Y465207D01*
Y464874D01*
X1778371Y464499D01*
X1778163Y464207D01*
X1777913Y463999D01*
X1777496Y463832D01*
X1777121Y463790D01*
X1776746Y463874D01*
X1776496Y463999D01*
X1776246Y464249D01*
X1776079Y464540D01*
X1775996Y464832D01*
Y465124D01*
X1776079Y465415D01*
X1776204Y465665D01*
X1776371Y465874D01*
G01X1777038Y467140D02*
X1777329Y467432D01*
X1777496Y467682D01*
X1777579Y468015D01*
X1777496Y468307D01*
X1777329Y468515D01*
X1777079Y468682D01*
X1776788Y468724D01*
X1776538Y468682D01*
X1776288Y468515D01*
X1776079Y468265D01*
X1775996Y467974D01*
X1776079Y467640D01*
X1776329Y467349D01*
X1776704Y467182D01*
X1777121Y467140D01*
X1777663Y467224D01*
X1777954Y467349D01*
X1778246Y467557D01*
X1778454Y467849D01*
X1778496Y468140D01*
X1778413Y468432D01*
X1778204Y468640D01*
G01X1775996Y471032D02*
X1776038Y471324D01*
X1776163Y471657D01*
X1776371Y471865D01*
X1776663Y471949D01*
X1776954Y471865D01*
X1777204Y471615D01*
X1777329Y471240D01*
Y470824D01*
X1777413Y470574D01*
X1777621Y470365D01*
X1777913Y470282D01*
X1778204Y470407D01*
X1778413Y470699D01*
X1778496Y471032D01*
X1778413Y471365D01*
X1778204Y471657D01*
X1777913Y471782D01*
X1777621Y471699D01*
X1777413Y471490D01*
X1777329Y471240D01*
Y470824D01*
X1777204Y470449D01*
X1776954Y470199D01*
X1776663Y470115D01*
X1776371Y470199D01*
X1776163Y470407D01*
X1776038Y470740D01*
X1775996Y471032D01*
G01X1778496Y474132D02*
X1778413Y473799D01*
X1778204Y473549D01*
X1777954Y473382D01*
X1777621Y473257D01*
X1777246Y473215D01*
X1776871Y473257D01*
X1776538Y473382D01*
X1776288Y473549D01*
X1776079Y473799D01*
X1775996Y474132D01*
X1776079Y474465D01*
X1776288Y474715D01*
X1776538Y474882D01*
X1776871Y475007D01*
X1777246Y475049D01*
X1777621Y475007D01*
X1777954Y474882D01*
X1778204Y474715D01*
X1778413Y474465D01*
X1778496Y474132D01*
G01X1756479Y465182D02*
Y462682D01*
X1754813D01*
G01X1752546D02*
X1752254Y462724D01*
X1751921Y462849D01*
X1751713Y463057D01*
X1751629Y463349D01*
X1751713Y463640D01*
X1751963Y463890D01*
X1752338Y464015D01*
X1752754D01*
X1753004Y464099D01*
X1753213Y464307D01*
X1753296Y464599D01*
X1753171Y464890D01*
X1752879Y465099D01*
X1752546Y465182D01*
X1752213Y465099D01*
X1751921Y464890D01*
X1751796Y464599D01*
X1751879Y464307D01*
X1752088Y464099D01*
X1752338Y464015D01*
X1752754D01*
X1753129Y463890D01*
X1753379Y463640D01*
X1753463Y463349D01*
X1753379Y463057D01*
X1753171Y462849D01*
X1752838Y462724D01*
X1752546Y462682D01*
G01X1741096Y460782D02*
Y419382D01*
X1791696D01*
Y460782D01*
X1741096D01*
G01X1730113Y434682D02*
Y432890D01*
X1729946Y432515D01*
X1729613Y432265D01*
X1729196Y432182D01*
X1728779Y432265D01*
X1728446Y432515D01*
X1728279Y432890D01*
Y434682D01*
G01X1727013Y432682D02*
X1726763Y432390D01*
X1726429Y432224D01*
X1726054Y432182D01*
X1725721Y432224D01*
X1725388Y432432D01*
X1725179Y432682D01*
X1725138Y432932D01*
X1725221Y433224D01*
X1725513Y433432D01*
X1725804Y433515D01*
X1726179D01*
G01X1725804D02*
X1725554Y433640D01*
X1725346Y433849D01*
X1725263Y434099D01*
X1725346Y434349D01*
X1725554Y434557D01*
X1725929Y434682D01*
X1726304Y434640D01*
X1726679Y434474D01*
G01X1722496Y432182D02*
Y434682D01*
X1724038Y432890D01*
X1721954D01*
G01X1739446Y442182D02*
Y437182D01*
X1734446D01*
G01X1738439Y443308D02*
X1741439D01*
G01X1738439Y453151D02*
X1740439D01*
G01X1793496Y452167D02*
Y463367D01*
G01X1811496Y452167D02*
X1793496D01*
G01X1811496Y463367D02*
Y452167D01*
G01X1806096Y410982D02*
Y408482D01*
G01X1807054Y410982D02*
X1805138D01*
G01X1802079Y410774D02*
X1802329Y410899D01*
X1802621Y410982D01*
X1802954D01*
X1803329Y410857D01*
X1803621Y410649D01*
X1803829Y410399D01*
X1803996Y409982D01*
X1804038Y409607D01*
X1803954Y409232D01*
X1803829Y408982D01*
X1803579Y408732D01*
X1803288Y408565D01*
X1802996Y408482D01*
X1802704D01*
X1802413Y408565D01*
X1802163Y408690D01*
X1801954Y408857D01*
G01X1799979Y408482D02*
X1799896Y409024D01*
X1799771Y409482D01*
X1799604Y409899D01*
X1799396Y410357D01*
X1799063Y410982D01*
X1800729D01*
G01X1811496Y451267D02*
Y440067D01*
G01X1793496Y451267D02*
X1811496D01*
G01X1793496Y440067D02*
Y451267D01*
G01X1811496Y412867D02*
Y424067D01*
G01X1793496Y412867D02*
X1811496D01*
G01X1793496Y424067D02*
Y412867D01*
G01X1771229Y484774D02*
X1771479Y484899D01*
X1771771Y484982D01*
X1772104D01*
X1772479Y484857D01*
X1772771Y484649D01*
X1772979Y484399D01*
X1773146Y483982D01*
X1773188Y483607D01*
X1773104Y483232D01*
X1772979Y482982D01*
X1772729Y482732D01*
X1772438Y482565D01*
X1772146Y482482D01*
X1771854D01*
X1771563Y482565D01*
X1771313Y482690D01*
X1771104Y482857D01*
G01X1769838Y483524D02*
X1769546Y483815D01*
X1769296Y483982D01*
X1768963Y484065D01*
X1768671Y483982D01*
X1768463Y483815D01*
X1768296Y483565D01*
X1768254Y483274D01*
X1768296Y483024D01*
X1768463Y482774D01*
X1768713Y482565D01*
X1769004Y482482D01*
X1769338Y482565D01*
X1769629Y482815D01*
X1769796Y483190D01*
X1769838Y483607D01*
X1769754Y484149D01*
X1769629Y484440D01*
X1769421Y484732D01*
X1769129Y484940D01*
X1768838Y484982D01*
X1768546Y484899D01*
X1768338Y484690D01*
G01X1765946Y482482D02*
X1765654Y482524D01*
X1765321Y482649D01*
X1765113Y482857D01*
X1765029Y483149D01*
X1765113Y483440D01*
X1765363Y483690D01*
X1765738Y483815D01*
X1766154D01*
X1766404Y483899D01*
X1766613Y484107D01*
X1766696Y484399D01*
X1766571Y484690D01*
X1766279Y484899D01*
X1765946Y484982D01*
X1765613Y484899D01*
X1765321Y484690D01*
X1765196Y484399D01*
X1765279Y484107D01*
X1765488Y483899D01*
X1765738Y483815D01*
X1766154D01*
X1766529Y483690D01*
X1766779Y483440D01*
X1766863Y483149D01*
X1766779Y482857D01*
X1766571Y482649D01*
X1766238Y482524D01*
X1765946Y482482D01*
G01X1763763Y482982D02*
X1763513Y482690D01*
X1763179Y482524D01*
X1762804Y482482D01*
X1762471Y482524D01*
X1762138Y482732D01*
X1761929Y482982D01*
X1761888Y483232D01*
X1761971Y483524D01*
X1762263Y483732D01*
X1762554Y483815D01*
X1762929D01*
G01X1762554D02*
X1762304Y483940D01*
X1762096Y484149D01*
X1762013Y484399D01*
X1762096Y484649D01*
X1762304Y484857D01*
X1762679Y484982D01*
X1763054Y484940D01*
X1763429Y484774D01*
G01X1737929Y486474D02*
X1738179Y486599D01*
X1738471Y486682D01*
X1738804D01*
X1739179Y486557D01*
X1739471Y486349D01*
X1739679Y486099D01*
X1739846Y485682D01*
X1739888Y485307D01*
X1739804Y484932D01*
X1739679Y484682D01*
X1739429Y484432D01*
X1739138Y484265D01*
X1738846Y484182D01*
X1738554D01*
X1738263Y484265D01*
X1738013Y484390D01*
X1737804Y484557D01*
G01X1736538Y485224D02*
X1736246Y485515D01*
X1735996Y485682D01*
X1735663Y485765D01*
X1735371Y485682D01*
X1735163Y485515D01*
X1734996Y485265D01*
X1734954Y484974D01*
X1734996Y484724D01*
X1735163Y484474D01*
X1735413Y484265D01*
X1735704Y484182D01*
X1736038Y484265D01*
X1736329Y484515D01*
X1736496Y484890D01*
X1736538Y485307D01*
X1736454Y485849D01*
X1736329Y486140D01*
X1736121Y486432D01*
X1735829Y486640D01*
X1735538Y486682D01*
X1735246Y486599D01*
X1735038Y486390D01*
G01X1732646Y484182D02*
X1732354Y484224D01*
X1732021Y484349D01*
X1731813Y484557D01*
X1731729Y484849D01*
X1731813Y485140D01*
X1732063Y485390D01*
X1732438Y485515D01*
X1732854D01*
X1733104Y485599D01*
X1733313Y485807D01*
X1733396Y486099D01*
X1733271Y486390D01*
X1732979Y486599D01*
X1732646Y486682D01*
X1732313Y486599D01*
X1732021Y486390D01*
X1731896Y486099D01*
X1731979Y485807D01*
X1732188Y485599D01*
X1732438Y485515D01*
X1732854D01*
X1733229Y485390D01*
X1733479Y485140D01*
X1733563Y484849D01*
X1733479Y484557D01*
X1733271Y484349D01*
X1732938Y484224D01*
X1732646Y484182D01*
G01X1729046D02*
Y486682D01*
X1730588Y484890D01*
X1728504D01*
G01X1739829Y480182D02*
Y482682D01*
X1738788D01*
X1738454Y482557D01*
X1738246Y482390D01*
X1738163Y482057D01*
X1738246Y481724D01*
X1738496Y481515D01*
X1738788Y481390D01*
X1739829D01*
G01X1738788D02*
X1738163Y480182D01*
G01X1735896D02*
Y482682D01*
X1736396Y482182D01*
G01Y480182D02*
X1735396D01*
G01X1732796D02*
Y482682D01*
X1733296Y482182D01*
G01Y480182D02*
X1732296D01*
G01X1730488Y481224D02*
X1730196Y481515D01*
X1729946Y481682D01*
X1729613Y481765D01*
X1729321Y481682D01*
X1729113Y481515D01*
X1728946Y481265D01*
X1728904Y480974D01*
X1728946Y480724D01*
X1729113Y480474D01*
X1729363Y480265D01*
X1729654Y480182D01*
X1729988Y480265D01*
X1730279Y480515D01*
X1730446Y480890D01*
X1730488Y481307D01*
X1730404Y481849D01*
X1730279Y482140D01*
X1730071Y482432D01*
X1729779Y482640D01*
X1729488Y482682D01*
X1729196Y482599D01*
X1728988Y482390D01*
G01X1727388Y481224D02*
X1727096Y481515D01*
X1726846Y481682D01*
X1726513Y481765D01*
X1726221Y481682D01*
X1726013Y481515D01*
X1725846Y481265D01*
X1725804Y480974D01*
X1725846Y480724D01*
X1726013Y480474D01*
X1726263Y480265D01*
X1726554Y480182D01*
X1726888Y480265D01*
X1727179Y480515D01*
X1727346Y480890D01*
X1727388Y481307D01*
X1727304Y481849D01*
X1727179Y482140D01*
X1726971Y482432D01*
X1726679Y482640D01*
X1726388Y482682D01*
X1726096Y482599D01*
X1725888Y482390D01*
G01X1757329Y480882D02*
Y483382D01*
X1756288D01*
X1755954Y483257D01*
X1755746Y483090D01*
X1755663Y482757D01*
X1755746Y482424D01*
X1755996Y482215D01*
X1756288Y482090D01*
X1757329D01*
G01X1756288D02*
X1755663Y480882D01*
G01X1753396D02*
Y483382D01*
X1753896Y482882D01*
G01Y480882D02*
X1752896D01*
G01X1750296D02*
Y483382D01*
X1750796Y482882D01*
G01Y480882D02*
X1749796D01*
G01X1747988Y481924D02*
X1747696Y482215D01*
X1747446Y482382D01*
X1747113Y482465D01*
X1746821Y482382D01*
X1746613Y482215D01*
X1746446Y481965D01*
X1746404Y481674D01*
X1746446Y481424D01*
X1746613Y481174D01*
X1746863Y480965D01*
X1747154Y480882D01*
X1747488Y480965D01*
X1747779Y481215D01*
X1747946Y481590D01*
X1747988Y482007D01*
X1747904Y482549D01*
X1747779Y482840D01*
X1747571Y483132D01*
X1747279Y483340D01*
X1746988Y483382D01*
X1746696Y483299D01*
X1746488Y483090D01*
G01X1745013Y481382D02*
X1744763Y481090D01*
X1744429Y480924D01*
X1744054Y480882D01*
X1743721Y480924D01*
X1743388Y481132D01*
X1743179Y481382D01*
X1743138Y481632D01*
X1743221Y481924D01*
X1743513Y482132D01*
X1743804Y482215D01*
X1744179D01*
G01X1743804D02*
X1743554Y482340D01*
X1743346Y482549D01*
X1743263Y482799D01*
X1743346Y483049D01*
X1743554Y483257D01*
X1743929Y483382D01*
X1744304Y483340D01*
X1744679Y483174D01*
G01X1806096Y496482D02*
Y493982D01*
G01X1807054Y496482D02*
X1805138D01*
G01X1802079Y496274D02*
X1802329Y496399D01*
X1802621Y496482D01*
X1802954D01*
X1803329Y496357D01*
X1803621Y496149D01*
X1803829Y495899D01*
X1803996Y495482D01*
X1804038Y495107D01*
X1803954Y494732D01*
X1803829Y494482D01*
X1803579Y494232D01*
X1803288Y494065D01*
X1802996Y493982D01*
X1802704D01*
X1802413Y494065D01*
X1802163Y494190D01*
X1801954Y494357D01*
G01X1799896Y493982D02*
X1799604Y494024D01*
X1799271Y494149D01*
X1799063Y494357D01*
X1798979Y494649D01*
X1799063Y494940D01*
X1799313Y495190D01*
X1799688Y495315D01*
X1800104D01*
X1800354Y495399D01*
X1800563Y495607D01*
X1800646Y495899D01*
X1800521Y496190D01*
X1800229Y496399D01*
X1799896Y496482D01*
X1799563Y496399D01*
X1799271Y496190D01*
X1799146Y495899D01*
X1799229Y495607D01*
X1799438Y495399D01*
X1799688Y495315D01*
X1800104D01*
X1800479Y495190D01*
X1800729Y494940D01*
X1800813Y494649D01*
X1800729Y494357D01*
X1800521Y494149D01*
X1800188Y494024D01*
X1799896Y493982D01*
G01X1793496Y490567D02*
Y479367D01*
G01X1811496Y490567D02*
X1793496D01*
G01X1811496Y479367D02*
Y490567D01*
G01X1815500Y895100D02*
Y853700D01*
X1866100D01*
Y895100D01*
X1815500D01*
G01X1778792Y860267D02*
X1778917Y860017D01*
X1779000Y859725D01*
Y859392D01*
X1778875Y859017D01*
X1778667Y858725D01*
X1778417Y858517D01*
X1778000Y858350D01*
X1777625Y858308D01*
X1777250Y858392D01*
X1777000Y858517D01*
X1776750Y858767D01*
X1776583Y859058D01*
X1776500Y859350D01*
Y859642D01*
X1776583Y859933D01*
X1776708Y860183D01*
X1776875Y860392D01*
G01X1777542Y861658D02*
X1777833Y861950D01*
X1778000Y862200D01*
X1778083Y862533D01*
X1778000Y862825D01*
X1777833Y863033D01*
X1777583Y863200D01*
X1777292Y863242D01*
X1777042Y863200D01*
X1776792Y863033D01*
X1776583Y862783D01*
X1776500Y862492D01*
X1776583Y862158D01*
X1776833Y861867D01*
X1777208Y861700D01*
X1777625Y861658D01*
X1778167Y861742D01*
X1778458Y861867D01*
X1778750Y862075D01*
X1778958Y862367D01*
X1779000Y862658D01*
X1778917Y862950D01*
X1778708Y863158D01*
G01X1776875Y864633D02*
X1776667Y864883D01*
X1776542Y865175D01*
X1776500Y865550D01*
X1776583Y865925D01*
X1776750Y866217D01*
X1777042Y866425D01*
X1777375Y866467D01*
X1777708Y866383D01*
X1777917Y866175D01*
X1778083Y865883D01*
X1778125Y865592D01*
X1778083Y865300D01*
X1777917Y864925D01*
X1779000Y865050D01*
Y866175D01*
G01X1777542Y867858D02*
X1777833Y868150D01*
X1778000Y868400D01*
X1778083Y868733D01*
X1778000Y869025D01*
X1777833Y869233D01*
X1777583Y869400D01*
X1777292Y869442D01*
X1777042Y869400D01*
X1776792Y869233D01*
X1776583Y868983D01*
X1776500Y868692D01*
X1776583Y868358D01*
X1776833Y868067D01*
X1777208Y867900D01*
X1777625Y867858D01*
X1778167Y867942D01*
X1778458Y868067D01*
X1778750Y868275D01*
X1778958Y868567D01*
X1779000Y868858D01*
X1778917Y869150D01*
X1778708Y869358D01*
G01X1815433Y926992D02*
X1815683Y927117D01*
X1815975Y927200D01*
X1816308D01*
X1816683Y927075D01*
X1816975Y926867D01*
X1817183Y926617D01*
X1817350Y926200D01*
X1817392Y925825D01*
X1817308Y925450D01*
X1817183Y925200D01*
X1816933Y924950D01*
X1816642Y924783D01*
X1816350Y924700D01*
X1816058D01*
X1815767Y924783D01*
X1815517Y924908D01*
X1815308Y925075D01*
G01X1814042Y925742D02*
X1813750Y926033D01*
X1813500Y926200D01*
X1813167Y926283D01*
X1812875Y926200D01*
X1812667Y926033D01*
X1812500Y925783D01*
X1812458Y925492D01*
X1812500Y925242D01*
X1812667Y924992D01*
X1812917Y924783D01*
X1813208Y924700D01*
X1813542Y924783D01*
X1813833Y925033D01*
X1814000Y925408D01*
X1814042Y925825D01*
X1813958Y926367D01*
X1813833Y926658D01*
X1813625Y926950D01*
X1813333Y927158D01*
X1813042Y927200D01*
X1812750Y927117D01*
X1812542Y926908D01*
G01X1810942Y925742D02*
X1810650Y926033D01*
X1810400Y926200D01*
X1810067Y926283D01*
X1809775Y926200D01*
X1809567Y926033D01*
X1809400Y925783D01*
X1809358Y925492D01*
X1809400Y925242D01*
X1809567Y924992D01*
X1809817Y924783D01*
X1810108Y924700D01*
X1810442Y924783D01*
X1810733Y925033D01*
X1810900Y925408D01*
X1810942Y925825D01*
X1810858Y926367D01*
X1810733Y926658D01*
X1810525Y926950D01*
X1810233Y927158D01*
X1809942Y927200D01*
X1809650Y927117D01*
X1809442Y926908D01*
G01X1807842Y925742D02*
X1807550Y926033D01*
X1807300Y926200D01*
X1806967Y926283D01*
X1806675Y926200D01*
X1806467Y926033D01*
X1806300Y925783D01*
X1806258Y925492D01*
X1806300Y925242D01*
X1806467Y924992D01*
X1806717Y924783D01*
X1807008Y924700D01*
X1807342Y924783D01*
X1807633Y925033D01*
X1807800Y925408D01*
X1807842Y925825D01*
X1807758Y926367D01*
X1807633Y926658D01*
X1807425Y926950D01*
X1807133Y927158D01*
X1806842Y927200D01*
X1806550Y927117D01*
X1806342Y926908D01*
G01X1799000Y913967D02*
X1801500D01*
Y915008D01*
X1801375Y915342D01*
X1801208Y915550D01*
X1800875Y915633D01*
X1800542Y915550D01*
X1800333Y915300D01*
X1800208Y915008D01*
Y913967D01*
G01Y915008D02*
X1799000Y915633D01*
G01Y917900D02*
X1801500D01*
X1801000Y917400D01*
G01X1799000D02*
Y918400D01*
G01Y921000D02*
X1801500D01*
X1801000Y920500D01*
G01X1799000D02*
Y921500D01*
G01X1799375Y923183D02*
X1799167Y923433D01*
X1799042Y923725D01*
X1799000Y924100D01*
X1799083Y924475D01*
X1799250Y924767D01*
X1799542Y924975D01*
X1799875Y925017D01*
X1800208Y924933D01*
X1800417Y924725D01*
X1800583Y924433D01*
X1800625Y924142D01*
X1800583Y923850D01*
X1800417Y923475D01*
X1801500Y923600D01*
Y924725D01*
G01Y927200D02*
X1801417Y926867D01*
X1801208Y926617D01*
X1800958Y926450D01*
X1800625Y926325D01*
X1800250Y926283D01*
X1799875Y926325D01*
X1799542Y926450D01*
X1799292Y926617D01*
X1799083Y926867D01*
X1799000Y927200D01*
X1799083Y927533D01*
X1799292Y927783D01*
X1799542Y927950D01*
X1799875Y928075D01*
X1800250Y928117D01*
X1800625Y928075D01*
X1800958Y927950D01*
X1801208Y927783D01*
X1801417Y927533D01*
X1801500Y927200D01*
G01X1805941Y900016D02*
X1801941D01*
Y907416D01*
G01X1817033Y920700D02*
Y923200D01*
X1815992D01*
X1815658Y923075D01*
X1815450Y922908D01*
X1815367Y922575D01*
X1815450Y922242D01*
X1815700Y922033D01*
X1815992Y921908D01*
X1817033D01*
G01X1815992D02*
X1815367Y920700D01*
G01X1813100D02*
Y923200D01*
X1813600Y922700D01*
G01Y920700D02*
X1812600D01*
G01X1810000D02*
Y923200D01*
X1810500Y922700D01*
G01Y920700D02*
X1809500D01*
G01X1806400D02*
Y923200D01*
X1807942Y921408D01*
X1805858D01*
G01X1803883Y920700D02*
X1803800Y921242D01*
X1803675Y921700D01*
X1803508Y922117D01*
X1803300Y922575D01*
X1802967Y923200D01*
X1804633D01*
G01X1807500Y902300D02*
Y906300D01*
X1814900D01*
G01X1779233Y901792D02*
X1779483Y901917D01*
X1779775Y902000D01*
X1780108D01*
X1780483Y901875D01*
X1780775Y901667D01*
X1780983Y901417D01*
X1781150Y901000D01*
X1781192Y900625D01*
X1781108Y900250D01*
X1780983Y900000D01*
X1780733Y899750D01*
X1780442Y899583D01*
X1780150Y899500D01*
X1779858D01*
X1779567Y899583D01*
X1779317Y899708D01*
X1779108Y899875D01*
G01X1777842Y900542D02*
X1777550Y900833D01*
X1777300Y901000D01*
X1776967Y901083D01*
X1776675Y901000D01*
X1776467Y900833D01*
X1776300Y900583D01*
X1776258Y900292D01*
X1776300Y900042D01*
X1776467Y899792D01*
X1776717Y899583D01*
X1777008Y899500D01*
X1777342Y899583D01*
X1777633Y899833D01*
X1777800Y900208D01*
X1777842Y900625D01*
X1777758Y901167D01*
X1777633Y901458D01*
X1777425Y901750D01*
X1777133Y901958D01*
X1776842Y902000D01*
X1776550Y901917D01*
X1776342Y901708D01*
G01X1774742Y900542D02*
X1774450Y900833D01*
X1774200Y901000D01*
X1773867Y901083D01*
X1773575Y901000D01*
X1773367Y900833D01*
X1773200Y900583D01*
X1773158Y900292D01*
X1773200Y900042D01*
X1773367Y899792D01*
X1773617Y899583D01*
X1773908Y899500D01*
X1774242Y899583D01*
X1774533Y899833D01*
X1774700Y900208D01*
X1774742Y900625D01*
X1774658Y901167D01*
X1774533Y901458D01*
X1774325Y901750D01*
X1774033Y901958D01*
X1773742Y902000D01*
X1773450Y901917D01*
X1773242Y901708D01*
G01X1771767Y900000D02*
X1771517Y899708D01*
X1771183Y899542D01*
X1770808Y899500D01*
X1770475Y899542D01*
X1770142Y899750D01*
X1769933Y900000D01*
X1769892Y900250D01*
X1769975Y900542D01*
X1770267Y900750D01*
X1770558Y900833D01*
X1770933D01*
G01X1770558D02*
X1770308Y900958D01*
X1770100Y901167D01*
X1770017Y901417D01*
X1770100Y901667D01*
X1770308Y901875D01*
X1770683Y902000D01*
X1771058Y901958D01*
X1771433Y901792D01*
G01X1746500Y883467D02*
X1749000D01*
Y884508D01*
X1748875Y884842D01*
X1748708Y885050D01*
X1748375Y885133D01*
X1748042Y885050D01*
X1747833Y884800D01*
X1747708Y884508D01*
Y883467D01*
G01Y884508D02*
X1746500Y885133D01*
G01Y887400D02*
X1749000D01*
X1748500Y886900D01*
G01X1746500D02*
Y887900D01*
G01Y890500D02*
X1749000D01*
X1748500Y890000D01*
G01X1746500D02*
Y891000D01*
G01X1747000Y892683D02*
X1746708Y892933D01*
X1746542Y893267D01*
X1746500Y893642D01*
X1746542Y893975D01*
X1746750Y894308D01*
X1747000Y894517D01*
X1747250Y894558D01*
X1747542Y894475D01*
X1747750Y894183D01*
X1747833Y893892D01*
Y893517D01*
G01Y893892D02*
X1747958Y894142D01*
X1748167Y894350D01*
X1748417Y894433D01*
X1748667Y894350D01*
X1748875Y894142D01*
X1749000Y893767D01*
X1748958Y893392D01*
X1748792Y893017D01*
G01X1746500Y896617D02*
X1747042Y896700D01*
X1747500Y896825D01*
X1747917Y896992D01*
X1748375Y897200D01*
X1749000Y897533D01*
Y895867D01*
G01X1772292Y859767D02*
X1772417Y859517D01*
X1772500Y859225D01*
Y858892D01*
X1772375Y858517D01*
X1772167Y858225D01*
X1771917Y858017D01*
X1771500Y857850D01*
X1771125Y857808D01*
X1770750Y857892D01*
X1770500Y858017D01*
X1770250Y858267D01*
X1770083Y858558D01*
X1770000Y858850D01*
Y859142D01*
X1770083Y859433D01*
X1770208Y859683D01*
X1770375Y859892D01*
G01X1771042Y861158D02*
X1771333Y861450D01*
X1771500Y861700D01*
X1771583Y862033D01*
X1771500Y862325D01*
X1771333Y862533D01*
X1771083Y862700D01*
X1770792Y862742D01*
X1770542Y862700D01*
X1770292Y862533D01*
X1770083Y862283D01*
X1770000Y861992D01*
X1770083Y861658D01*
X1770333Y861367D01*
X1770708Y861200D01*
X1771125Y861158D01*
X1771667Y861242D01*
X1771958Y861367D01*
X1772250Y861575D01*
X1772458Y861867D01*
X1772500Y862158D01*
X1772417Y862450D01*
X1772208Y862658D01*
G01X1770375Y864133D02*
X1770167Y864383D01*
X1770042Y864675D01*
X1770000Y865050D01*
X1770083Y865425D01*
X1770250Y865717D01*
X1770542Y865925D01*
X1770875Y865967D01*
X1771208Y865883D01*
X1771417Y865675D01*
X1771583Y865383D01*
X1771625Y865092D01*
X1771583Y864800D01*
X1771417Y864425D01*
X1772500Y864550D01*
Y865675D01*
G01X1770500Y867233D02*
X1770208Y867483D01*
X1770042Y867817D01*
X1770000Y868192D01*
X1770042Y868525D01*
X1770250Y868858D01*
X1770500Y869067D01*
X1770750Y869108D01*
X1771042Y869025D01*
X1771250Y868733D01*
X1771333Y868442D01*
Y868067D01*
G01Y868442D02*
X1771458Y868692D01*
X1771667Y868900D01*
X1771917Y868983D01*
X1772167Y868900D01*
X1772375Y868692D01*
X1772500Y868317D01*
X1772458Y867942D01*
X1772292Y867567D01*
G01X1764292Y859767D02*
X1764417Y859517D01*
X1764500Y859225D01*
Y858892D01*
X1764375Y858517D01*
X1764167Y858225D01*
X1763917Y858017D01*
X1763500Y857850D01*
X1763125Y857808D01*
X1762750Y857892D01*
X1762500Y858017D01*
X1762250Y858267D01*
X1762083Y858558D01*
X1762000Y858850D01*
Y859142D01*
X1762083Y859433D01*
X1762208Y859683D01*
X1762375Y859892D01*
G01X1763042Y861158D02*
X1763333Y861450D01*
X1763500Y861700D01*
X1763583Y862033D01*
X1763500Y862325D01*
X1763333Y862533D01*
X1763083Y862700D01*
X1762792Y862742D01*
X1762542Y862700D01*
X1762292Y862533D01*
X1762083Y862283D01*
X1762000Y861992D01*
X1762083Y861658D01*
X1762333Y861367D01*
X1762708Y861200D01*
X1763125Y861158D01*
X1763667Y861242D01*
X1763958Y861367D01*
X1764250Y861575D01*
X1764458Y861867D01*
X1764500Y862158D01*
X1764417Y862450D01*
X1764208Y862658D01*
G01X1762375Y864133D02*
X1762167Y864383D01*
X1762042Y864675D01*
X1762000Y865050D01*
X1762083Y865425D01*
X1762250Y865717D01*
X1762542Y865925D01*
X1762875Y865967D01*
X1763208Y865883D01*
X1763417Y865675D01*
X1763583Y865383D01*
X1763625Y865092D01*
X1763583Y864800D01*
X1763417Y864425D01*
X1764500Y864550D01*
Y865675D01*
G01X1762000Y868650D02*
X1764500D01*
X1762708Y867108D01*
Y869192D01*
G01X1756792Y891267D02*
X1756917Y891017D01*
X1757000Y890725D01*
Y890392D01*
X1756875Y890017D01*
X1756667Y889725D01*
X1756417Y889517D01*
X1756000Y889350D01*
X1755625Y889308D01*
X1755250Y889392D01*
X1755000Y889517D01*
X1754750Y889767D01*
X1754583Y890058D01*
X1754500Y890350D01*
Y890642D01*
X1754583Y890933D01*
X1754708Y891183D01*
X1754875Y891392D01*
G01X1755542Y892658D02*
X1755833Y892950D01*
X1756000Y893200D01*
X1756083Y893533D01*
X1756000Y893825D01*
X1755833Y894033D01*
X1755583Y894200D01*
X1755292Y894242D01*
X1755042Y894200D01*
X1754792Y894033D01*
X1754583Y893783D01*
X1754500Y893492D01*
X1754583Y893158D01*
X1754833Y892867D01*
X1755208Y892700D01*
X1755625Y892658D01*
X1756167Y892742D01*
X1756458Y892867D01*
X1756750Y893075D01*
X1756958Y893367D01*
X1757000Y893658D01*
X1756917Y893950D01*
X1756708Y894158D01*
G01X1754875Y895633D02*
X1754667Y895883D01*
X1754542Y896175D01*
X1754500Y896550D01*
X1754583Y896925D01*
X1754750Y897217D01*
X1755042Y897425D01*
X1755375Y897467D01*
X1755708Y897383D01*
X1755917Y897175D01*
X1756083Y896883D01*
X1756125Y896592D01*
X1756083Y896300D01*
X1755917Y895925D01*
X1757000Y896050D01*
Y897175D01*
G01X1754875Y898733D02*
X1754667Y898983D01*
X1754542Y899275D01*
X1754500Y899650D01*
X1754583Y900025D01*
X1754750Y900317D01*
X1755042Y900525D01*
X1755375Y900567D01*
X1755708Y900483D01*
X1755917Y900275D01*
X1756083Y899983D01*
X1756125Y899692D01*
X1756083Y899400D01*
X1755917Y899025D01*
X1757000Y899150D01*
Y900275D01*
G01X1779233Y906292D02*
X1779483Y906417D01*
X1779775Y906500D01*
X1780108D01*
X1780483Y906375D01*
X1780775Y906167D01*
X1780983Y905917D01*
X1781150Y905500D01*
X1781192Y905125D01*
X1781108Y904750D01*
X1780983Y904500D01*
X1780733Y904250D01*
X1780442Y904083D01*
X1780150Y904000D01*
X1779858D01*
X1779567Y904083D01*
X1779317Y904208D01*
X1779108Y904375D01*
G01X1777842Y905042D02*
X1777550Y905333D01*
X1777300Y905500D01*
X1776967Y905583D01*
X1776675Y905500D01*
X1776467Y905333D01*
X1776300Y905083D01*
X1776258Y904792D01*
X1776300Y904542D01*
X1776467Y904292D01*
X1776717Y904083D01*
X1777008Y904000D01*
X1777342Y904083D01*
X1777633Y904333D01*
X1777800Y904708D01*
X1777842Y905125D01*
X1777758Y905667D01*
X1777633Y905958D01*
X1777425Y906250D01*
X1777133Y906458D01*
X1776842Y906500D01*
X1776550Y906417D01*
X1776342Y906208D01*
G01X1774742Y905042D02*
X1774450Y905333D01*
X1774200Y905500D01*
X1773867Y905583D01*
X1773575Y905500D01*
X1773367Y905333D01*
X1773200Y905083D01*
X1773158Y904792D01*
X1773200Y904542D01*
X1773367Y904292D01*
X1773617Y904083D01*
X1773908Y904000D01*
X1774242Y904083D01*
X1774533Y904333D01*
X1774700Y904708D01*
X1774742Y905125D01*
X1774658Y905667D01*
X1774533Y905958D01*
X1774325Y906250D01*
X1774033Y906458D01*
X1773742Y906500D01*
X1773450Y906417D01*
X1773242Y906208D01*
G01X1770850Y906500D02*
X1771183Y906417D01*
X1771433Y906208D01*
X1771600Y905958D01*
X1771725Y905625D01*
X1771767Y905250D01*
X1771725Y904875D01*
X1771600Y904542D01*
X1771433Y904292D01*
X1771183Y904083D01*
X1770850Y904000D01*
X1770517Y904083D01*
X1770267Y904292D01*
X1770100Y904542D01*
X1769975Y904875D01*
X1769933Y905250D01*
X1769975Y905625D01*
X1770100Y905958D01*
X1770267Y906208D01*
X1770517Y906417D01*
X1770850Y906500D01*
G01X1795300Y915250D02*
X1794467D01*
Y914500D01*
X1794717Y914250D01*
X1795008Y914083D01*
X1795425Y914000D01*
X1795842Y914083D01*
X1796133Y914250D01*
X1796383Y914500D01*
X1796550Y914792D01*
X1796633Y915125D01*
Y915417D01*
X1796550Y915667D01*
X1796383Y915958D01*
X1796133Y916208D01*
X1795883Y916375D01*
X1795550Y916500D01*
X1795258D01*
X1794925Y916417D01*
X1794675Y916250D01*
G01X1793242Y915042D02*
X1792950Y915333D01*
X1792700Y915500D01*
X1792367Y915583D01*
X1792075Y915500D01*
X1791867Y915333D01*
X1791700Y915083D01*
X1791658Y914792D01*
X1791700Y914542D01*
X1791867Y914292D01*
X1792117Y914083D01*
X1792408Y914000D01*
X1792742Y914083D01*
X1793033Y914333D01*
X1793200Y914708D01*
X1793242Y915125D01*
X1793158Y915667D01*
X1793033Y915958D01*
X1792825Y916250D01*
X1792533Y916458D01*
X1792242Y916500D01*
X1791950Y916417D01*
X1791742Y916208D01*
G01X1752383Y860000D02*
Y857500D01*
X1750717D01*
G01X1749367Y857875D02*
X1749117Y857667D01*
X1748825Y857542D01*
X1748450Y857500D01*
X1748075Y857583D01*
X1747783Y857750D01*
X1747575Y858042D01*
X1747533Y858375D01*
X1747617Y858708D01*
X1747825Y858917D01*
X1748117Y859083D01*
X1748408Y859125D01*
X1748700Y859083D01*
X1749075Y858917D01*
X1748950Y860000D01*
X1747825D01*
G01X1757963Y862925D02*
X1744563D01*
G01X1757963Y870125D02*
Y862925D01*
G01X1744563Y870125D02*
X1757963D01*
G01X1744563Y862925D02*
Y870125D01*
G01X1803017Y869500D02*
Y867708D01*
X1802850Y867333D01*
X1802517Y867083D01*
X1802100Y867000D01*
X1801683Y867083D01*
X1801350Y867333D01*
X1801183Y867708D01*
Y869500D01*
G01X1799917Y867500D02*
X1799667Y867208D01*
X1799333Y867042D01*
X1798958Y867000D01*
X1798625Y867042D01*
X1798292Y867250D01*
X1798083Y867500D01*
X1798042Y867750D01*
X1798125Y868042D01*
X1798417Y868250D01*
X1798708Y868333D01*
X1799083D01*
G01X1798708D02*
X1798458Y868458D01*
X1798250Y868667D01*
X1798167Y868917D01*
X1798250Y869167D01*
X1798458Y869375D01*
X1798833Y869500D01*
X1799208Y869458D01*
X1799583Y869292D01*
G01X1796817Y867500D02*
X1796567Y867208D01*
X1796233Y867042D01*
X1795858Y867000D01*
X1795525Y867042D01*
X1795192Y867250D01*
X1794983Y867500D01*
X1794942Y867750D01*
X1795025Y868042D01*
X1795317Y868250D01*
X1795608Y868333D01*
X1795983D01*
G01X1795608D02*
X1795358Y868458D01*
X1795150Y868667D01*
X1795067Y868917D01*
X1795150Y869167D01*
X1795358Y869375D01*
X1795733Y869500D01*
X1796108Y869458D01*
X1796483Y869292D01*
G01X1786150Y894500D02*
Y899500D01*
X1791150D01*
G01Y871500D02*
X1786150D01*
Y876500D01*
G01X1813850D02*
Y871500D01*
X1808850D01*
G01X1787157Y891406D02*
X1784157D01*
G01X1787157Y881563D02*
X1785157D01*
G01X1812843Y877626D02*
X1815843D01*
G01X1812843Y887469D02*
X1814843D01*
G01X1820767Y477165D02*
X1820892Y476915D01*
X1820975Y476623D01*
Y476290D01*
X1820850Y475915D01*
X1820642Y475623D01*
X1820392Y475415D01*
X1819975Y475248D01*
X1819600Y475206D01*
X1819225Y475290D01*
X1818975Y475415D01*
X1818725Y475665D01*
X1818558Y475956D01*
X1818475Y476248D01*
Y476540D01*
X1818558Y476831D01*
X1818683Y477081D01*
X1818850Y477290D01*
G01X1819517Y478556D02*
X1819808Y478848D01*
X1819975Y479098D01*
X1820058Y479431D01*
X1819975Y479723D01*
X1819808Y479931D01*
X1819558Y480098D01*
X1819267Y480140D01*
X1819017Y480098D01*
X1818767Y479931D01*
X1818558Y479681D01*
X1818475Y479390D01*
X1818558Y479056D01*
X1818808Y478765D01*
X1819183Y478598D01*
X1819600Y478556D01*
X1820142Y478640D01*
X1820433Y478765D01*
X1820725Y478973D01*
X1820933Y479265D01*
X1820975Y479556D01*
X1820892Y479848D01*
X1820683Y480056D01*
G01X1818475Y482448D02*
X1818517Y482740D01*
X1818642Y483073D01*
X1818850Y483281D01*
X1819142Y483365D01*
X1819433Y483281D01*
X1819683Y483031D01*
X1819808Y482656D01*
Y482240D01*
X1819892Y481990D01*
X1820100Y481781D01*
X1820392Y481698D01*
X1820683Y481823D01*
X1820892Y482115D01*
X1820975Y482448D01*
X1820892Y482781D01*
X1820683Y483073D01*
X1820392Y483198D01*
X1820100Y483115D01*
X1819892Y482906D01*
X1819808Y482656D01*
Y482240D01*
X1819683Y481865D01*
X1819433Y481615D01*
X1819142Y481531D01*
X1818850Y481615D01*
X1818642Y481823D01*
X1818517Y482156D01*
X1818475Y482448D01*
G01X1819517Y484756D02*
X1819808Y485048D01*
X1819975Y485298D01*
X1820058Y485631D01*
X1819975Y485923D01*
X1819808Y486131D01*
X1819558Y486298D01*
X1819267Y486340D01*
X1819017Y486298D01*
X1818767Y486131D01*
X1818558Y485881D01*
X1818475Y485590D01*
X1818558Y485256D01*
X1818808Y484965D01*
X1819183Y484798D01*
X1819600Y484756D01*
X1820142Y484840D01*
X1820433Y484965D01*
X1820725Y485173D01*
X1820933Y485465D01*
X1820975Y485756D01*
X1820892Y486048D01*
X1820683Y486256D01*
G01X1833027Y477169D02*
X1833152Y476919D01*
X1833235Y476627D01*
Y476294D01*
X1833110Y475919D01*
X1832902Y475627D01*
X1832652Y475419D01*
X1832235Y475252D01*
X1831860Y475210D01*
X1831485Y475294D01*
X1831235Y475419D01*
X1830985Y475669D01*
X1830818Y475960D01*
X1830735Y476252D01*
Y476544D01*
X1830818Y476835D01*
X1830943Y477085D01*
X1831110Y477294D01*
G01X1831777Y478560D02*
X1832068Y478852D01*
X1832235Y479102D01*
X1832318Y479435D01*
X1832235Y479727D01*
X1832068Y479935D01*
X1831818Y480102D01*
X1831527Y480144D01*
X1831277Y480102D01*
X1831027Y479935D01*
X1830818Y479685D01*
X1830735Y479394D01*
X1830818Y479060D01*
X1831068Y478769D01*
X1831443Y478602D01*
X1831860Y478560D01*
X1832402Y478644D01*
X1832693Y478769D01*
X1832985Y478977D01*
X1833193Y479269D01*
X1833235Y479560D01*
X1833152Y479852D01*
X1832943Y480060D01*
G01X1830735Y482452D02*
X1830777Y482744D01*
X1830902Y483077D01*
X1831110Y483285D01*
X1831402Y483369D01*
X1831693Y483285D01*
X1831943Y483035D01*
X1832068Y482660D01*
Y482244D01*
X1832152Y481994D01*
X1832360Y481785D01*
X1832652Y481702D01*
X1832943Y481827D01*
X1833152Y482119D01*
X1833235Y482452D01*
X1833152Y482785D01*
X1832943Y483077D01*
X1832652Y483202D01*
X1832360Y483119D01*
X1832152Y482910D01*
X1832068Y482660D01*
Y482244D01*
X1831943Y481869D01*
X1831693Y481619D01*
X1831402Y481535D01*
X1831110Y481619D01*
X1830902Y481827D01*
X1830777Y482160D01*
X1830735Y482452D01*
G01Y485469D02*
X1831277Y485552D01*
X1831735Y485677D01*
X1832152Y485844D01*
X1832610Y486052D01*
X1833235Y486385D01*
Y484719D01*
G01X1825916Y477161D02*
X1826041Y476911D01*
X1826124Y476619D01*
Y476286D01*
X1825999Y475911D01*
X1825791Y475619D01*
X1825541Y475411D01*
X1825124Y475244D01*
X1824749Y475202D01*
X1824374Y475286D01*
X1824124Y475411D01*
X1823874Y475661D01*
X1823707Y475952D01*
X1823624Y476244D01*
Y476536D01*
X1823707Y476827D01*
X1823832Y477077D01*
X1823999Y477286D01*
G01X1824666Y478552D02*
X1824957Y478844D01*
X1825124Y479094D01*
X1825207Y479427D01*
X1825124Y479719D01*
X1824957Y479927D01*
X1824707Y480094D01*
X1824416Y480136D01*
X1824166Y480094D01*
X1823916Y479927D01*
X1823707Y479677D01*
X1823624Y479386D01*
X1823707Y479052D01*
X1823957Y478761D01*
X1824332Y478594D01*
X1824749Y478552D01*
X1825291Y478636D01*
X1825582Y478761D01*
X1825874Y478969D01*
X1826082Y479261D01*
X1826124Y479552D01*
X1826041Y479844D01*
X1825832Y480052D01*
G01X1823624Y482444D02*
X1823666Y482736D01*
X1823791Y483069D01*
X1823999Y483277D01*
X1824291Y483361D01*
X1824582Y483277D01*
X1824832Y483027D01*
X1824957Y482652D01*
Y482236D01*
X1825041Y481986D01*
X1825249Y481777D01*
X1825541Y481694D01*
X1825832Y481819D01*
X1826041Y482111D01*
X1826124Y482444D01*
X1826041Y482777D01*
X1825832Y483069D01*
X1825541Y483194D01*
X1825249Y483111D01*
X1825041Y482902D01*
X1824957Y482652D01*
Y482236D01*
X1824832Y481861D01*
X1824582Y481611D01*
X1824291Y481527D01*
X1823999Y481611D01*
X1823791Y481819D01*
X1823666Y482152D01*
X1823624Y482444D01*
G01Y485544D02*
X1823666Y485836D01*
X1823791Y486169D01*
X1823999Y486377D01*
X1824291Y486461D01*
X1824582Y486377D01*
X1824832Y486127D01*
X1824957Y485752D01*
Y485336D01*
X1825041Y485086D01*
X1825249Y484877D01*
X1825541Y484794D01*
X1825832Y484919D01*
X1826041Y485211D01*
X1826124Y485544D01*
X1826041Y485877D01*
X1825832Y486169D01*
X1825541Y486294D01*
X1825249Y486211D01*
X1825041Y486002D01*
X1824957Y485752D01*
Y485336D01*
X1824832Y484961D01*
X1824582Y484711D01*
X1824291Y484627D01*
X1823999Y484711D01*
X1823791Y484919D01*
X1823666Y485252D01*
X1823624Y485544D01*
G01X1837024Y476802D02*
Y477635D01*
X1836274D01*
X1836024Y477385D01*
X1835857Y477094D01*
X1835774Y476677D01*
X1835857Y476260D01*
X1836024Y475969D01*
X1836274Y475719D01*
X1836566Y475552D01*
X1836899Y475469D01*
X1837191D01*
X1837441Y475552D01*
X1837732Y475719D01*
X1837982Y475969D01*
X1838149Y476219D01*
X1838274Y476552D01*
Y476844D01*
X1838191Y477177D01*
X1838024Y477427D01*
G01X1835774Y479569D02*
X1836316Y479652D01*
X1836774Y479777D01*
X1837191Y479944D01*
X1837649Y480152D01*
X1838274Y480485D01*
Y478819D01*
G01X1881150Y846000D02*
Y843500D01*
G01X1882108Y846000D02*
X1880192D01*
G01X1877133Y845792D02*
X1877383Y845917D01*
X1877675Y846000D01*
X1878008D01*
X1878383Y845875D01*
X1878675Y845667D01*
X1878883Y845417D01*
X1879050Y845000D01*
X1879092Y844625D01*
X1879008Y844250D01*
X1878883Y844000D01*
X1878633Y843750D01*
X1878342Y843583D01*
X1878050Y843500D01*
X1877758D01*
X1877467Y843583D01*
X1877217Y843708D01*
X1877008Y843875D01*
G01X1874950Y843500D02*
Y846000D01*
X1875450Y845500D01*
G01Y843500D02*
X1874450D01*
G01X1871850Y846000D02*
X1872183Y845917D01*
X1872433Y845708D01*
X1872600Y845458D01*
X1872725Y845125D01*
X1872767Y844750D01*
X1872725Y844375D01*
X1872600Y844042D01*
X1872433Y843792D01*
X1872183Y843583D01*
X1871850Y843500D01*
X1871517Y843583D01*
X1871267Y843792D01*
X1871100Y844042D01*
X1870975Y844375D01*
X1870933Y844750D01*
X1870975Y845125D01*
X1871100Y845458D01*
X1871267Y845708D01*
X1871517Y845917D01*
X1871850Y846000D01*
G01X1885600Y847385D02*
Y858585D01*
G01X1867600Y847385D02*
X1885600D01*
G01X1867600Y858585D02*
Y847385D01*
G01X1853233Y916292D02*
X1853483Y916417D01*
X1853775Y916500D01*
X1854108D01*
X1854483Y916375D01*
X1854775Y916167D01*
X1854983Y915917D01*
X1855150Y915500D01*
X1855192Y915125D01*
X1855108Y914750D01*
X1854983Y914500D01*
X1854733Y914250D01*
X1854442Y914083D01*
X1854150Y914000D01*
X1853858D01*
X1853567Y914083D01*
X1853317Y914208D01*
X1853108Y914375D01*
G01X1851842Y915042D02*
X1851550Y915333D01*
X1851300Y915500D01*
X1850967Y915583D01*
X1850675Y915500D01*
X1850467Y915333D01*
X1850300Y915083D01*
X1850258Y914792D01*
X1850300Y914542D01*
X1850467Y914292D01*
X1850717Y914083D01*
X1851008Y914000D01*
X1851342Y914083D01*
X1851633Y914333D01*
X1851800Y914708D01*
X1851842Y915125D01*
X1851758Y915667D01*
X1851633Y915958D01*
X1851425Y916250D01*
X1851133Y916458D01*
X1850842Y916500D01*
X1850550Y916417D01*
X1850342Y916208D01*
G01X1848742Y915042D02*
X1848450Y915333D01*
X1848200Y915500D01*
X1847867Y915583D01*
X1847575Y915500D01*
X1847367Y915333D01*
X1847200Y915083D01*
X1847158Y914792D01*
X1847200Y914542D01*
X1847367Y914292D01*
X1847617Y914083D01*
X1847908Y914000D01*
X1848242Y914083D01*
X1848533Y914333D01*
X1848700Y914708D01*
X1848742Y915125D01*
X1848658Y915667D01*
X1848533Y915958D01*
X1848325Y916250D01*
X1848033Y916458D01*
X1847742Y916500D01*
X1847450Y916417D01*
X1847242Y916208D01*
G01X1845767Y914375D02*
X1845517Y914167D01*
X1845225Y914042D01*
X1844850Y914000D01*
X1844475Y914083D01*
X1844183Y914250D01*
X1843975Y914542D01*
X1843933Y914875D01*
X1844017Y915208D01*
X1844225Y915417D01*
X1844517Y915583D01*
X1844808Y915625D01*
X1845100Y915583D01*
X1845475Y915417D01*
X1845350Y916500D01*
X1844225D01*
G01X1845500Y897967D02*
X1848000D01*
Y899008D01*
X1847875Y899342D01*
X1847708Y899550D01*
X1847375Y899633D01*
X1847042Y899550D01*
X1846833Y899300D01*
X1846708Y899008D01*
Y897967D01*
G01Y899008D02*
X1845500Y899633D01*
G01Y901900D02*
X1848000D01*
X1847500Y901400D01*
G01X1845500D02*
Y902400D01*
G01Y905000D02*
X1848000D01*
X1847500Y904500D01*
G01X1845500D02*
Y905500D01*
G01Y908600D02*
X1848000D01*
X1846208Y907058D01*
Y909142D01*
G01X1845500Y911200D02*
X1848000D01*
X1847500Y910700D01*
G01X1845500D02*
Y911700D01*
G01X1838736Y898274D02*
X1834736D01*
Y905674D01*
G01X1852292Y899767D02*
X1852417Y899517D01*
X1852500Y899225D01*
Y898892D01*
X1852375Y898517D01*
X1852167Y898225D01*
X1851917Y898017D01*
X1851500Y897850D01*
X1851125Y897808D01*
X1850750Y897892D01*
X1850500Y898017D01*
X1850250Y898267D01*
X1850083Y898558D01*
X1850000Y898850D01*
Y899142D01*
X1850083Y899433D01*
X1850208Y899683D01*
X1850375Y899892D01*
G01X1851042Y901158D02*
X1851333Y901450D01*
X1851500Y901700D01*
X1851583Y902033D01*
X1851500Y902325D01*
X1851333Y902533D01*
X1851083Y902700D01*
X1850792Y902742D01*
X1850542Y902700D01*
X1850292Y902533D01*
X1850083Y902283D01*
X1850000Y901992D01*
X1850083Y901658D01*
X1850333Y901367D01*
X1850708Y901200D01*
X1851125Y901158D01*
X1851667Y901242D01*
X1851958Y901367D01*
X1852250Y901575D01*
X1852458Y901867D01*
X1852500Y902158D01*
X1852417Y902450D01*
X1852208Y902658D01*
G01X1851042Y904258D02*
X1851333Y904550D01*
X1851500Y904800D01*
X1851583Y905133D01*
X1851500Y905425D01*
X1851333Y905633D01*
X1851083Y905800D01*
X1850792Y905842D01*
X1850542Y905800D01*
X1850292Y905633D01*
X1850083Y905383D01*
X1850000Y905092D01*
X1850083Y904758D01*
X1850333Y904467D01*
X1850708Y904300D01*
X1851125Y904258D01*
X1851667Y904342D01*
X1851958Y904467D01*
X1852250Y904675D01*
X1852458Y904967D01*
X1852500Y905258D01*
X1852417Y905550D01*
X1852208Y905758D01*
G01X1850000Y908650D02*
X1852500D01*
X1850708Y907108D01*
Y909192D01*
G01X1834333Y916100D02*
Y918600D01*
X1833292D01*
X1832958Y918475D01*
X1832750Y918308D01*
X1832667Y917975D01*
X1832750Y917642D01*
X1833000Y917433D01*
X1833292Y917308D01*
X1834333D01*
G01X1833292D02*
X1832667Y916100D01*
G01X1830400D02*
Y918600D01*
X1830900Y918100D01*
G01Y916100D02*
X1829900D01*
G01X1827300D02*
Y918600D01*
X1827800Y918100D01*
G01Y916100D02*
X1826800D01*
G01X1823700D02*
Y918600D01*
X1825242Y916808D01*
X1823158D01*
G01X1820600Y916100D02*
Y918600D01*
X1822142Y916808D01*
X1820058D01*
G01X1894792Y911267D02*
X1894917Y911017D01*
X1895000Y910725D01*
Y910392D01*
X1894875Y910017D01*
X1894667Y909725D01*
X1894417Y909517D01*
X1894000Y909350D01*
X1893625Y909308D01*
X1893250Y909392D01*
X1893000Y909517D01*
X1892750Y909767D01*
X1892583Y910058D01*
X1892500Y910350D01*
Y910642D01*
X1892583Y910933D01*
X1892708Y911183D01*
X1892875Y911392D01*
G01X1893542Y912658D02*
X1893833Y912950D01*
X1894000Y913200D01*
X1894083Y913533D01*
X1894000Y913825D01*
X1893833Y914033D01*
X1893583Y914200D01*
X1893292Y914242D01*
X1893042Y914200D01*
X1892792Y914033D01*
X1892583Y913783D01*
X1892500Y913492D01*
X1892583Y913158D01*
X1892833Y912867D01*
X1893208Y912700D01*
X1893625Y912658D01*
X1894167Y912742D01*
X1894458Y912867D01*
X1894750Y913075D01*
X1894958Y913367D01*
X1895000Y913658D01*
X1894917Y913950D01*
X1894708Y914158D01*
G01X1893542Y915758D02*
X1893833Y916050D01*
X1894000Y916300D01*
X1894083Y916633D01*
X1894000Y916925D01*
X1893833Y917133D01*
X1893583Y917300D01*
X1893292Y917342D01*
X1893042Y917300D01*
X1892792Y917133D01*
X1892583Y916883D01*
X1892500Y916592D01*
X1892583Y916258D01*
X1892833Y915967D01*
X1893208Y915800D01*
X1893625Y915758D01*
X1894167Y915842D01*
X1894458Y915967D01*
X1894750Y916175D01*
X1894958Y916467D01*
X1895000Y916758D01*
X1894917Y917050D01*
X1894708Y917258D01*
G01X1892500Y919650D02*
X1892542Y919942D01*
X1892667Y920275D01*
X1892875Y920483D01*
X1893167Y920567D01*
X1893458Y920483D01*
X1893708Y920233D01*
X1893833Y919858D01*
Y919442D01*
X1893917Y919192D01*
X1894125Y918983D01*
X1894417Y918900D01*
X1894708Y919025D01*
X1894917Y919317D01*
X1895000Y919650D01*
X1894917Y919983D01*
X1894708Y920275D01*
X1894417Y920400D01*
X1894125Y920317D01*
X1893917Y920108D01*
X1893833Y919858D01*
Y919442D01*
X1893708Y919067D01*
X1893458Y918817D01*
X1893167Y918733D01*
X1892875Y918817D01*
X1892667Y919025D01*
X1892542Y919358D01*
X1892500Y919650D01*
G01X1907292Y911267D02*
X1907417Y911017D01*
X1907500Y910725D01*
Y910392D01*
X1907375Y910017D01*
X1907167Y909725D01*
X1906917Y909517D01*
X1906500Y909350D01*
X1906125Y909308D01*
X1905750Y909392D01*
X1905500Y909517D01*
X1905250Y909767D01*
X1905083Y910058D01*
X1905000Y910350D01*
Y910642D01*
X1905083Y910933D01*
X1905208Y911183D01*
X1905375Y911392D01*
G01X1906042Y912658D02*
X1906333Y912950D01*
X1906500Y913200D01*
X1906583Y913533D01*
X1906500Y913825D01*
X1906333Y914033D01*
X1906083Y914200D01*
X1905792Y914242D01*
X1905542Y914200D01*
X1905292Y914033D01*
X1905083Y913783D01*
X1905000Y913492D01*
X1905083Y913158D01*
X1905333Y912867D01*
X1905708Y912700D01*
X1906125Y912658D01*
X1906667Y912742D01*
X1906958Y912867D01*
X1907250Y913075D01*
X1907458Y913367D01*
X1907500Y913658D01*
X1907417Y913950D01*
X1907208Y914158D01*
G01X1906042Y915758D02*
X1906333Y916050D01*
X1906500Y916300D01*
X1906583Y916633D01*
X1906500Y916925D01*
X1906333Y917133D01*
X1906083Y917300D01*
X1905792Y917342D01*
X1905542Y917300D01*
X1905292Y917133D01*
X1905083Y916883D01*
X1905000Y916592D01*
X1905083Y916258D01*
X1905333Y915967D01*
X1905708Y915800D01*
X1906125Y915758D01*
X1906667Y915842D01*
X1906958Y915967D01*
X1907250Y916175D01*
X1907458Y916467D01*
X1907500Y916758D01*
X1907417Y917050D01*
X1907208Y917258D01*
G01X1905292Y918942D02*
X1905083Y919233D01*
X1905000Y919567D01*
X1905083Y919900D01*
X1905333Y920192D01*
X1905708Y920400D01*
X1906083Y920483D01*
X1906542D01*
X1906917Y920400D01*
X1907250Y920192D01*
X1907417Y919942D01*
X1907500Y919650D01*
X1907417Y919317D01*
X1907250Y919067D01*
X1907000Y918900D01*
X1906667Y918817D01*
X1906375Y918900D01*
X1906083Y919108D01*
X1905917Y919358D01*
X1905875Y919650D01*
X1905958Y919983D01*
X1906167Y920233D01*
X1906542Y920483D01*
G01X1899792Y911267D02*
X1899917Y911017D01*
X1900000Y910725D01*
Y910392D01*
X1899875Y910017D01*
X1899667Y909725D01*
X1899417Y909517D01*
X1899000Y909350D01*
X1898625Y909308D01*
X1898250Y909392D01*
X1898000Y909517D01*
X1897750Y909767D01*
X1897583Y910058D01*
X1897500Y910350D01*
Y910642D01*
X1897583Y910933D01*
X1897708Y911183D01*
X1897875Y911392D01*
G01X1898542Y912658D02*
X1898833Y912950D01*
X1899000Y913200D01*
X1899083Y913533D01*
X1899000Y913825D01*
X1898833Y914033D01*
X1898583Y914200D01*
X1898292Y914242D01*
X1898042Y914200D01*
X1897792Y914033D01*
X1897583Y913783D01*
X1897500Y913492D01*
X1897583Y913158D01*
X1897833Y912867D01*
X1898208Y912700D01*
X1898625Y912658D01*
X1899167Y912742D01*
X1899458Y912867D01*
X1899750Y913075D01*
X1899958Y913367D01*
X1900000Y913658D01*
X1899917Y913950D01*
X1899708Y914158D01*
G01X1897500Y916467D02*
X1898042Y916550D01*
X1898500Y916675D01*
X1898917Y916842D01*
X1899375Y917050D01*
X1900000Y917383D01*
Y915717D01*
G01Y919650D02*
X1899917Y919317D01*
X1899708Y919067D01*
X1899458Y918900D01*
X1899125Y918775D01*
X1898750Y918733D01*
X1898375Y918775D01*
X1898042Y918900D01*
X1897792Y919067D01*
X1897583Y919317D01*
X1897500Y919650D01*
X1897583Y919983D01*
X1897792Y920233D01*
X1898042Y920400D01*
X1898375Y920525D01*
X1898750Y920567D01*
X1899125Y920525D01*
X1899458Y920400D01*
X1899708Y920233D01*
X1899917Y919983D01*
X1900000Y919650D01*
G01X1912750Y910200D02*
Y911033D01*
X1912000D01*
X1911750Y910783D01*
X1911583Y910492D01*
X1911500Y910075D01*
X1911583Y909658D01*
X1911750Y909367D01*
X1912000Y909117D01*
X1912292Y908950D01*
X1912625Y908867D01*
X1912917D01*
X1913167Y908950D01*
X1913458Y909117D01*
X1913708Y909367D01*
X1913875Y909617D01*
X1914000Y909950D01*
Y910242D01*
X1913917Y910575D01*
X1913750Y910825D01*
G01X1911875Y912133D02*
X1911667Y912383D01*
X1911542Y912675D01*
X1911500Y913050D01*
X1911583Y913425D01*
X1911750Y913717D01*
X1912042Y913925D01*
X1912375Y913967D01*
X1912708Y913883D01*
X1912917Y913675D01*
X1913083Y913383D01*
X1913125Y913092D01*
X1913083Y912800D01*
X1912917Y912425D01*
X1914000Y912550D01*
Y913675D01*
G01X1831883Y899500D02*
Y897000D01*
X1830217D01*
G01X1828742Y898042D02*
X1828450Y898333D01*
X1828200Y898500D01*
X1827867Y898583D01*
X1827575Y898500D01*
X1827367Y898333D01*
X1827200Y898083D01*
X1827158Y897792D01*
X1827200Y897542D01*
X1827367Y897292D01*
X1827617Y897083D01*
X1827908Y897000D01*
X1828242Y897083D01*
X1828533Y897333D01*
X1828700Y897708D01*
X1828742Y898125D01*
X1828658Y898667D01*
X1828533Y898958D01*
X1828325Y899250D01*
X1828033Y899458D01*
X1827742Y899500D01*
X1827450Y899417D01*
X1827242Y899208D01*
G01X1880100Y930500D02*
Y928000D01*
G01X1881058Y930500D02*
X1879142D01*
G01X1876083Y930292D02*
X1876333Y930417D01*
X1876625Y930500D01*
X1876958D01*
X1877333Y930375D01*
X1877625Y930167D01*
X1877833Y929917D01*
X1878000Y929500D01*
X1878042Y929125D01*
X1877958Y928750D01*
X1877833Y928500D01*
X1877583Y928250D01*
X1877292Y928083D01*
X1877000Y928000D01*
X1876708D01*
X1876417Y928083D01*
X1876167Y928208D01*
X1875958Y928375D01*
G01X1874608Y928292D02*
X1874317Y928083D01*
X1873983Y928000D01*
X1873650Y928083D01*
X1873358Y928333D01*
X1873150Y928708D01*
X1873067Y929083D01*
Y929542D01*
X1873150Y929917D01*
X1873358Y930250D01*
X1873608Y930417D01*
X1873900Y930500D01*
X1874233Y930417D01*
X1874483Y930250D01*
X1874650Y930000D01*
X1874733Y929667D01*
X1874650Y929375D01*
X1874442Y929083D01*
X1874192Y928917D01*
X1873900Y928875D01*
X1873567Y928958D01*
X1873317Y929167D01*
X1873067Y929542D01*
G01X1867600Y886685D02*
Y897885D01*
G01X1885600Y886685D02*
X1867600D01*
G01X1885600Y897885D02*
Y886685D01*
G01X1867600Y925085D02*
Y913885D01*
G01X1885600Y925085D02*
X1867600D01*
G01X1885600Y913885D02*
Y925085D01*
G01Y885785D02*
Y874585D01*
G01X1867600Y885785D02*
X1885600D01*
G01X1867600Y874585D02*
Y885785D01*
G54D15*
G01X62763Y885525D02*
Y889525D01*
G01X33063Y876025D02*
X34163D01*
G01X30363D02*
X31463D01*
G01X160590Y447789D02*
Y451789D01*
G01X132990Y441889D02*
X134090D01*
G01X130290D02*
X131390D01*
G01X129141Y901944D02*
X125141D01*
G01X107026Y904841D02*
Y905941D01*
G01Y902141D02*
Y903241D01*
G01X226968Y464208D02*
X222968D01*
G01X204853Y467105D02*
Y468205D01*
G01Y464405D02*
Y465505D01*
G01X1024563Y1112199D02*
Y1116199D01*
G01X999500Y1097000D02*
Y1101000D01*
G01X981500Y1124800D02*
Y1128800D01*
G01X971900Y1129800D02*
X967900D01*
G01X1020416Y1140321D02*
X1019316D01*
G01X1023116D02*
X1022016D01*
G01X1703359Y451207D02*
Y455207D01*
G01X1673659Y441707D02*
X1674759D01*
G01X1670959D02*
X1672059D01*
G01X1769737Y467626D02*
X1765737D01*
G01X1747622Y470523D02*
Y471623D01*
G01Y467823D02*
Y468923D01*
G01X1777763Y885525D02*
Y889525D01*
G01X1748063Y876025D02*
X1749163D01*
G01X1745363D02*
X1746463D01*
G01X1844141Y901944D02*
X1840141D01*
G01X1822026Y904841D02*
Y905941D01*
G01Y902141D02*
Y903241D01*
M02*
